FILE_TYPE = MACRO_DRAWING;
SET COLOR_WIRE YELLOW;
SET COLOR_PROP MONO;
SET COLOR_DOT WHITE;
SET COLOR_ARC YELLOW;
SET COLOR_BODY GREEN;
SET COLOR_NOTE MONO;
SET PROP_DISPLAY VALUE;
SET PAGE_NUMBER P68;
FORCEADD OFFPAGE..1
(-6925 3700);
FORCEPROP 2 LAST $XR0 34 
J 0
(-7146 3700);
DISPLAY 0.638298 (-7146 3700);
PAINT MONO (-7146 3700);
FORCEPROP 2 LAST CDS_LIB mstr_standard
J 0
(-6925 3700);
PAINT MONO (-6925 3700);
DISPLAY INVISIBLE (-6925 3700);
FORCEPROP 1 LAST OFFPAGE TRUE
J 0
(-6600 3575);
DISPLAY 1.170213 (-6600 3575);
PAINT GREEN (-6600 3575);
DISPLAY INVISIBLE (-6600 3575);
FORCEPROP 1 LAST COMMENT_BODY TRUE
J 0
(-6800 3600);
DISPLAY 1.170213 (-6800 3600);
PAINT GREEN (-6800 3600);
DISPLAY INVISIBLE (-6800 3600);
FORCEPROP 2 LAST PATH I1
J 0
(-6875 3775);
DISPLAY 1.021277 (-6875 3775);
PAINT ORANGE (-6875 3775);
DISPLAY INVISIBLE (-6875 3775);
FORCEADD TAP..1
R 2
(-5725 1900);
FORCEPROP 3 LASTPIN (-5675 1900) SIG_NAME UPI_CPU0_CPU1_P1P1_DN<5>
J 0
(-5665 1910);
DISPLAY 0.659574 (-5665 1910);
PAINT MONO (-5665 1910);
DISPLAY INVISIBLE (-5665 1910);
FORCEPROP 1 LASTPIN (-5675 1900) BN 5
J 2
(-5663 1908);
DISPLAY 0.617021 (-5663 1908);
PAINT GREEN (-5663 1908);
FORCEPROP 2 LAST CDS_LIB mstr_standard
J 0
(-5725 1900);
PAINT MONO (-5725 1900);
DISPLAY INVISIBLE (-5725 1900);
FORCEPROP 1 LAST BODY_TYPE PLUMBING
J 2
(-5725 1950);
DISPLAY 1.446809 (-5725 1950);
PAINT GREEN (-5725 1950);
DISPLAY INVISIBLE (-5725 1950);
FORCEPROP 1 LAST HDL_TAP TRUE
J 2
(-6050 1775);
DISPLAY 1.446809 (-6050 1775);
PAINT GREEN (-6050 1775);
DISPLAY INVISIBLE (-6050 1775);
FORCEPROP 1 LAST PATH I10
J 2
(-5723 1900);
DISPLAY 0.872340 (-5723 1900);
PAINT GREEN (-5723 1900);
DISPLAY INVISIBLE (-5723 1900);
FORCEADD TAP..1
(-2950 1700);
FORCEPROP 3 LASTPIN (-3000 1700) SIG_NAME UPI_CPU1_CPU0_P1P1_DP<1>
J 0
(-2990 1710);
DISPLAY 0.659574 (-2990 1710);
PAINT MONO (-2990 1710);
DISPLAY INVISIBLE (-2990 1710);
FORCEPROP 1 LASTPIN (-3000 1700) BN 1
J 0
(-3012 1708);
DISPLAY 0.617021 (-3012 1708);
PAINT GREEN (-3012 1708);
FORCEPROP 2 LAST CDS_LIB mstr_standard
J 0
(-2950 1700);
PAINT MONO (-2950 1700);
DISPLAY INVISIBLE (-2950 1700);
FORCEPROP 1 LAST BODY_TYPE PLUMBING
J 0
(-2950 1750);
DISPLAY 1.446809 (-2950 1750);
PAINT GREEN (-2950 1750);
DISPLAY INVISIBLE (-2950 1750);
FORCEPROP 1 LAST HDL_TAP TRUE
J 0
(-2625 1575);
DISPLAY 1.446809 (-2625 1575);
PAINT GREEN (-2625 1575);
DISPLAY INVISIBLE (-2625 1575);
FORCEPROP 1 LAST PATH I100
J 0
(-2952 1700);
DISPLAY 0.872340 (-2952 1700);
PAINT GREEN (-2952 1700);
DISPLAY INVISIBLE (-2952 1700);
FORCEADD TAP..1
(-2950 2950);
FORCEPROP 3 LASTPIN (-3000 2950) SIG_NAME UPI_CPU1_CPU0_P1P1_DP<5>
J 0
(-2990 2960);
DISPLAY 0.659574 (-2990 2960);
PAINT MONO (-2990 2960);
DISPLAY INVISIBLE (-2990 2960);
FORCEPROP 1 LASTPIN (-3000 2950) BN 5
J 0
(-3012 2958);
DISPLAY 0.617021 (-3012 2958);
PAINT GREEN (-3012 2958);
FORCEPROP 2 LAST CDS_LIB mstr_standard
J 0
(-2950 2950);
PAINT MONO (-2950 2950);
DISPLAY INVISIBLE (-2950 2950);
FORCEPROP 1 LAST BODY_TYPE PLUMBING
J 0
(-2950 3000);
DISPLAY 1.446809 (-2950 3000);
PAINT GREEN (-2950 3000);
DISPLAY INVISIBLE (-2950 3000);
FORCEPROP 1 LAST HDL_TAP TRUE
J 0
(-2625 2825);
DISPLAY 1.446809 (-2625 2825);
PAINT GREEN (-2625 2825);
DISPLAY INVISIBLE (-2625 2825);
FORCEPROP 1 LAST PATH I101
J 0
(-2952 2950);
DISPLAY 0.872340 (-2952 2950);
PAINT GREEN (-2952 2950);
DISPLAY INVISIBLE (-2952 2950);
FORCEADD TAP..1
(-2950 1950);
FORCEPROP 3 LASTPIN (-3000 1950) SIG_NAME UPI_CPU1_CPU0_P1P1_DP<6>
J 0
(-2990 1960);
DISPLAY 0.659574 (-2990 1960);
PAINT MONO (-2990 1960);
DISPLAY INVISIBLE (-2990 1960);
FORCEPROP 1 LASTPIN (-3000 1950) BN 6
J 0
(-3012 1958);
DISPLAY 0.617021 (-3012 1958);
PAINT GREEN (-3012 1958);
FORCEPROP 2 LAST CDS_LIB mstr_standard
J 0
(-2950 1950);
PAINT MONO (-2950 1950);
DISPLAY INVISIBLE (-2950 1950);
FORCEPROP 1 LAST BODY_TYPE PLUMBING
J 0
(-2950 2000);
DISPLAY 1.446809 (-2950 2000);
PAINT GREEN (-2950 2000);
DISPLAY INVISIBLE (-2950 2000);
FORCEPROP 1 LAST HDL_TAP TRUE
J 0
(-2625 1825);
DISPLAY 1.446809 (-2625 1825);
PAINT GREEN (-2625 1825);
DISPLAY INVISIBLE (-2625 1825);
FORCEPROP 1 LAST PATH I102
J 0
(-2952 1950);
DISPLAY 0.872340 (-2952 1950);
PAINT GREEN (-2952 1950);
DISPLAY INVISIBLE (-2952 1950);
FORCEADD TAP..1
(-2950 2000);
FORCEPROP 3 LASTPIN (-3000 2000) SIG_NAME UPI_CPU1_CPU0_P1P1_DP<7>
J 0
(-2990 2010);
DISPLAY 0.659574 (-2990 2010);
PAINT MONO (-2990 2010);
DISPLAY INVISIBLE (-2990 2010);
FORCEPROP 1 LASTPIN (-3000 2000) BN 7
J 0
(-3012 2008);
DISPLAY 0.617021 (-3012 2008);
PAINT GREEN (-3012 2008);
FORCEPROP 2 LAST CDS_LIB mstr_standard
J 0
(-2950 2000);
PAINT MONO (-2950 2000);
DISPLAY INVISIBLE (-2950 2000);
FORCEPROP 1 LAST BODY_TYPE PLUMBING
J 0
(-2950 2050);
DISPLAY 1.446809 (-2950 2050);
PAINT GREEN (-2950 2050);
DISPLAY INVISIBLE (-2950 2050);
FORCEPROP 1 LAST HDL_TAP TRUE
J 0
(-2625 1875);
DISPLAY 1.446809 (-2625 1875);
PAINT GREEN (-2625 1875);
DISPLAY INVISIBLE (-2625 1875);
FORCEPROP 1 LAST PATH I103
J 0
(-2952 2000);
DISPLAY 0.872340 (-2952 2000);
PAINT GREEN (-2952 2000);
DISPLAY INVISIBLE (-2952 2000);
FORCEADD TAP..1
(-2950 2050);
FORCEPROP 3 LASTPIN (-3000 2050) SIG_NAME UPI_CPU1_CPU0_P1P1_DP<8>
J 0
(-2990 2060);
DISPLAY 0.659574 (-2990 2060);
PAINT MONO (-2990 2060);
DISPLAY INVISIBLE (-2990 2060);
FORCEPROP 1 LASTPIN (-3000 2050) BN 8
J 0
(-3012 2058);
DISPLAY 0.617021 (-3012 2058);
PAINT GREEN (-3012 2058);
FORCEPROP 2 LAST CDS_LIB mstr_standard
J 0
(-2950 2050);
PAINT MONO (-2950 2050);
DISPLAY INVISIBLE (-2950 2050);
FORCEPROP 1 LAST BODY_TYPE PLUMBING
J 0
(-2950 2100);
DISPLAY 1.446809 (-2950 2100);
PAINT GREEN (-2950 2100);
DISPLAY INVISIBLE (-2950 2100);
FORCEPROP 1 LAST HDL_TAP TRUE
J 0
(-2625 1925);
DISPLAY 1.446809 (-2625 1925);
PAINT GREEN (-2625 1925);
DISPLAY INVISIBLE (-2625 1925);
FORCEPROP 1 LAST PATH I104
J 0
(-2952 2050);
DISPLAY 0.872340 (-2952 2050);
PAINT GREEN (-2952 2050);
DISPLAY INVISIBLE (-2952 2050);
FORCEADD TAP..1
(-2950 3150);
FORCEPROP 3 LASTPIN (-3000 3150) SIG_NAME UPI_CPU1_CPU0_P1P1_DP<9>
J 0
(-2990 3160);
DISPLAY 0.659574 (-2990 3160);
PAINT MONO (-2990 3160);
DISPLAY INVISIBLE (-2990 3160);
FORCEPROP 1 LASTPIN (-3000 3150) BN 9
J 0
(-3012 3158);
DISPLAY 0.617021 (-3012 3158);
PAINT GREEN (-3012 3158);
FORCEPROP 2 LAST CDS_LIB mstr_standard
J 0
(-2950 3150);
PAINT MONO (-2950 3150);
DISPLAY INVISIBLE (-2950 3150);
FORCEPROP 1 LAST BODY_TYPE PLUMBING
J 0
(-2950 3200);
DISPLAY 1.446809 (-2950 3200);
PAINT GREEN (-2950 3200);
DISPLAY INVISIBLE (-2950 3200);
FORCEPROP 1 LAST HDL_TAP TRUE
J 0
(-2625 3025);
DISPLAY 1.446809 (-2625 3025);
PAINT GREEN (-2625 3025);
DISPLAY INVISIBLE (-2625 3025);
FORCEPROP 1 LAST PATH I105
J 0
(-2952 3150);
DISPLAY 0.872340 (-2952 3150);
PAINT GREEN (-2952 3150);
DISPLAY INVISIBLE (-2952 3150);
FORCEADD TAP..1
(-2950 2200);
FORCEPROP 3 LASTPIN (-3000 2200) SIG_NAME UPI_CPU1_CPU0_P1P1_DP<11>
J 0
(-2990 2210);
DISPLAY 0.659574 (-2990 2210);
PAINT MONO (-2990 2210);
DISPLAY INVISIBLE (-2990 2210);
FORCEPROP 1 LASTPIN (-3000 2200) BN 11
J 0
(-3012 2208);
DISPLAY 0.617021 (-3012 2208);
PAINT GREEN (-3012 2208);
FORCEPROP 2 LAST CDS_LIB mstr_standard
J 0
(-2950 2200);
PAINT MONO (-2950 2200);
DISPLAY INVISIBLE (-2950 2200);
FORCEPROP 1 LAST BODY_TYPE PLUMBING
J 0
(-2950 2250);
DISPLAY 1.446809 (-2950 2250);
PAINT GREEN (-2950 2250);
DISPLAY INVISIBLE (-2950 2250);
FORCEPROP 1 LAST HDL_TAP TRUE
J 0
(-2625 2075);
DISPLAY 1.446809 (-2625 2075);
PAINT GREEN (-2625 2075);
DISPLAY INVISIBLE (-2625 2075);
FORCEPROP 1 LAST PATH I106
J 0
(-2952 2200);
DISPLAY 0.872340 (-2952 2200);
PAINT GREEN (-2952 2200);
DISPLAY INVISIBLE (-2952 2200);
FORCEADD TAP..1
(-2950 3350);
FORCEPROP 3 LASTPIN (-3000 3350) SIG_NAME UPI_CPU1_CPU0_P1P1_DP<13>
J 0
(-2990 3360);
DISPLAY 0.659574 (-2990 3360);
PAINT MONO (-2990 3360);
DISPLAY INVISIBLE (-2990 3360);
FORCEPROP 1 LASTPIN (-3000 3350) BN 13
J 0
(-3012 3358);
DISPLAY 0.617021 (-3012 3358);
PAINT GREEN (-3012 3358);
FORCEPROP 2 LAST CDS_LIB mstr_standard
J 0
(-2950 3350);
PAINT MONO (-2950 3350);
DISPLAY INVISIBLE (-2950 3350);
FORCEPROP 1 LAST BODY_TYPE PLUMBING
J 0
(-2950 3400);
DISPLAY 1.446809 (-2950 3400);
PAINT GREEN (-2950 3400);
DISPLAY INVISIBLE (-2950 3400);
FORCEPROP 1 LAST HDL_TAP TRUE
J 0
(-2625 3225);
DISPLAY 1.446809 (-2625 3225);
PAINT GREEN (-2625 3225);
DISPLAY INVISIBLE (-2625 3225);
FORCEPROP 1 LAST PATH I107
J 0
(-2952 3350);
DISPLAY 0.872340 (-2952 3350);
PAINT GREEN (-2952 3350);
DISPLAY INVISIBLE (-2952 3350);
FORCEADD TAP..1
(-2950 3400);
FORCEPROP 3 LASTPIN (-3000 3400) SIG_NAME UPI_CPU1_CPU0_P1P1_DP<14>
J 0
(-2990 3410);
DISPLAY 0.659574 (-2990 3410);
PAINT MONO (-2990 3410);
DISPLAY INVISIBLE (-2990 3410);
FORCEPROP 1 LASTPIN (-3000 3400) BN 14
J 0
(-3012 3408);
DISPLAY 0.617021 (-3012 3408);
PAINT GREEN (-3012 3408);
FORCEPROP 2 LAST CDS_LIB mstr_standard
J 0
(-2950 3400);
PAINT MONO (-2950 3400);
DISPLAY INVISIBLE (-2950 3400);
FORCEPROP 1 LAST BODY_TYPE PLUMBING
J 0
(-2950 3450);
DISPLAY 1.446809 (-2950 3450);
PAINT GREEN (-2950 3450);
DISPLAY INVISIBLE (-2950 3450);
FORCEPROP 1 LAST HDL_TAP TRUE
J 0
(-2625 3275);
DISPLAY 1.446809 (-2625 3275);
PAINT GREEN (-2625 3275);
DISPLAY INVISIBLE (-2625 3275);
FORCEPROP 1 LAST PATH I108
J 0
(-2952 3400);
DISPLAY 0.872340 (-2952 3400);
PAINT GREEN (-2952 3400);
DISPLAY INVISIBLE (-2952 3400);
FORCEADD TAP..1
(-2950 3450);
FORCEPROP 3 LASTPIN (-3000 3450) SIG_NAME UPI_CPU1_CPU0_P1P1_DP<15>
J 0
(-2990 3460);
DISPLAY 0.659574 (-2990 3460);
PAINT MONO (-2990 3460);
DISPLAY INVISIBLE (-2990 3460);
FORCEPROP 1 LASTPIN (-3000 3450) BN 15
J 0
(-3012 3458);
DISPLAY 0.617021 (-3012 3458);
PAINT GREEN (-3012 3458);
FORCEPROP 2 LAST CDS_LIB mstr_standard
J 0
(-2950 3450);
PAINT MONO (-2950 3450);
DISPLAY INVISIBLE (-2950 3450);
FORCEPROP 1 LAST BODY_TYPE PLUMBING
J 0
(-2950 3500);
DISPLAY 1.446809 (-2950 3500);
PAINT GREEN (-2950 3500);
DISPLAY INVISIBLE (-2950 3500);
FORCEPROP 1 LAST HDL_TAP TRUE
J 0
(-2625 3325);
DISPLAY 1.446809 (-2625 3325);
PAINT GREEN (-2625 3325);
DISPLAY INVISIBLE (-2625 3325);
FORCEPROP 1 LAST PATH I109
J 0
(-2952 3450);
DISPLAY 0.872340 (-2952 3450);
PAINT GREEN (-2952 3450);
DISPLAY INVISIBLE (-2952 3450);
FORCEADD TAP..1
R 2
(-5725 2000);
FORCEPROP 3 LASTPIN (-5675 2000) SIG_NAME UPI_CPU0_CPU1_P1P1_DN<7>
J 0
(-5665 2010);
DISPLAY 0.659574 (-5665 2010);
PAINT MONO (-5665 2010);
DISPLAY INVISIBLE (-5665 2010);
FORCEPROP 1 LASTPIN (-5675 2000) BN 7
J 2
(-5663 2008);
DISPLAY 0.617021 (-5663 2008);
PAINT GREEN (-5663 2008);
FORCEPROP 2 LAST CDS_LIB mstr_standard
J 0
(-5725 2000);
PAINT MONO (-5725 2000);
DISPLAY INVISIBLE (-5725 2000);
FORCEPROP 1 LAST BODY_TYPE PLUMBING
J 2
(-5725 2050);
DISPLAY 1.446809 (-5725 2050);
PAINT GREEN (-5725 2050);
DISPLAY INVISIBLE (-5725 2050);
FORCEPROP 1 LAST HDL_TAP TRUE
J 2
(-6050 1875);
DISPLAY 1.446809 (-6050 1875);
PAINT GREEN (-6050 1875);
DISPLAY INVISIBLE (-6050 1875);
FORCEPROP 1 LAST PATH I11
J 2
(-5723 2000);
DISPLAY 0.872340 (-5723 2000);
PAINT GREEN (-5723 2000);
DISPLAY INVISIBLE (-5723 2000);
FORCEADD TAP..1
(-2950 2550);
FORCEPROP 3 LASTPIN (-3000 2550) SIG_NAME UPI_CPU1_CPU0_P1P1_DP<18>
J 0
(-2990 2560);
DISPLAY 0.659574 (-2990 2560);
PAINT MONO (-2990 2560);
DISPLAY INVISIBLE (-2990 2560);
FORCEPROP 1 LASTPIN (-3000 2550) BN 18
J 0
(-3012 2558);
DISPLAY 0.617021 (-3012 2558);
PAINT GREEN (-3012 2558);
FORCEPROP 2 LAST CDS_LIB mstr_standard
J 0
(-2950 2550);
PAINT MONO (-2950 2550);
DISPLAY INVISIBLE (-2950 2550);
FORCEPROP 1 LAST BODY_TYPE PLUMBING
J 0
(-2950 2600);
DISPLAY 1.446809 (-2950 2600);
PAINT GREEN (-2950 2600);
DISPLAY INVISIBLE (-2950 2600);
FORCEPROP 1 LAST HDL_TAP TRUE
J 0
(-2625 2425);
DISPLAY 1.446809 (-2625 2425);
PAINT GREEN (-2625 2425);
DISPLAY INVISIBLE (-2625 2425);
FORCEPROP 1 LAST PATH I110
J 0
(-2952 2550);
DISPLAY 0.872340 (-2952 2550);
PAINT GREEN (-2952 2550);
DISPLAY INVISIBLE (-2952 2550);
FORCEADD TAP..1
(-2950 2600);
FORCEPROP 3 LASTPIN (-3000 2600) SIG_NAME UPI_CPU1_CPU0_P1P1_DP<19>
J 0
(-2990 2610);
DISPLAY 0.659574 (-2990 2610);
PAINT MONO (-2990 2610);
DISPLAY INVISIBLE (-2990 2610);
FORCEPROP 1 LASTPIN (-3000 2600) BN 19
J 0
(-3012 2608);
DISPLAY 0.617021 (-3012 2608);
PAINT GREEN (-3012 2608);
FORCEPROP 2 LAST CDS_LIB mstr_standard
J 0
(-2950 2600);
PAINT MONO (-2950 2600);
DISPLAY INVISIBLE (-2950 2600);
FORCEPROP 1 LAST BODY_TYPE PLUMBING
J 0
(-2950 2650);
DISPLAY 1.446809 (-2950 2650);
PAINT GREEN (-2950 2650);
DISPLAY INVISIBLE (-2950 2650);
FORCEPROP 1 LAST HDL_TAP TRUE
J 0
(-2625 2475);
DISPLAY 1.446809 (-2625 2475);
PAINT GREEN (-2625 2475);
DISPLAY INVISIBLE (-2625 2475);
FORCEPROP 1 LAST PATH I111
J 0
(-2952 2600);
DISPLAY 0.872340 (-2952 2600);
PAINT GREEN (-2952 2600);
DISPLAY INVISIBLE (-2952 2600);
FORCEADD TAP..1
(-2625 2700);
FORCEPROP 3 LASTPIN (-2675 2700) SIG_NAME UPI_CPU1_CPU0_P1P1_DN<0>
J 0
(-2665 2710);
DISPLAY 0.659574 (-2665 2710);
PAINT MONO (-2665 2710);
DISPLAY INVISIBLE (-2665 2710);
FORCEPROP 1 LASTPIN (-2675 2700) BN 0
J 0
(-2687 2708);
DISPLAY 0.617021 (-2687 2708);
PAINT GREEN (-2687 2708);
FORCEPROP 2 LAST CDS_LIB mstr_standard
J 0
(-2625 2700);
PAINT MONO (-2625 2700);
DISPLAY INVISIBLE (-2625 2700);
FORCEPROP 1 LAST BODY_TYPE PLUMBING
J 0
(-2625 2750);
DISPLAY 1.446809 (-2625 2750);
PAINT GREEN (-2625 2750);
DISPLAY INVISIBLE (-2625 2750);
FORCEPROP 1 LAST HDL_TAP TRUE
J 0
(-2300 2575);
DISPLAY 1.446809 (-2300 2575);
PAINT GREEN (-2300 2575);
DISPLAY INVISIBLE (-2300 2575);
FORCEPROP 1 LAST PATH I112
J 0
(-2627 2700);
DISPLAY 0.872340 (-2627 2700);
PAINT GREEN (-2627 2700);
DISPLAY INVISIBLE (-2627 2700);
FORCEADD TAP..1
(-2625 2750);
FORCEPROP 3 LASTPIN (-2675 2750) SIG_NAME UPI_CPU1_CPU0_P1P1_DN<1>
J 0
(-2665 2760);
DISPLAY 0.659574 (-2665 2760);
PAINT MONO (-2665 2760);
DISPLAY INVISIBLE (-2665 2760);
FORCEPROP 1 LASTPIN (-2675 2750) BN 1
J 0
(-2687 2758);
DISPLAY 0.617021 (-2687 2758);
PAINT GREEN (-2687 2758);
FORCEPROP 2 LAST CDS_LIB mstr_standard
J 0
(-2625 2750);
PAINT MONO (-2625 2750);
DISPLAY INVISIBLE (-2625 2750);
FORCEPROP 1 LAST BODY_TYPE PLUMBING
J 0
(-2625 2800);
DISPLAY 1.446809 (-2625 2800);
PAINT GREEN (-2625 2800);
DISPLAY INVISIBLE (-2625 2800);
FORCEPROP 1 LAST HDL_TAP TRUE
J 0
(-2300 2625);
DISPLAY 1.446809 (-2300 2625);
PAINT GREEN (-2300 2625);
DISPLAY INVISIBLE (-2300 2625);
FORCEPROP 1 LAST PATH I113
J 0
(-2627 2750);
DISPLAY 0.872340 (-2627 2750);
PAINT GREEN (-2627 2750);
DISPLAY INVISIBLE (-2627 2750);
FORCEADD TAP..1
(-2625 1900);
FORCEPROP 3 LASTPIN (-2675 1900) SIG_NAME UPI_CPU1_CPU0_P1P1_DN<5>
J 0
(-2665 1910);
DISPLAY 0.659574 (-2665 1910);
PAINT MONO (-2665 1910);
DISPLAY INVISIBLE (-2665 1910);
FORCEPROP 1 LASTPIN (-2675 1900) BN 5
J 0
(-2687 1908);
DISPLAY 0.617021 (-2687 1908);
PAINT GREEN (-2687 1908);
FORCEPROP 2 LAST CDS_LIB mstr_standard
J 0
(-2625 1900);
PAINT MONO (-2625 1900);
DISPLAY INVISIBLE (-2625 1900);
FORCEPROP 1 LAST BODY_TYPE PLUMBING
J 0
(-2625 1950);
DISPLAY 1.446809 (-2625 1950);
PAINT GREEN (-2625 1950);
DISPLAY INVISIBLE (-2625 1950);
FORCEPROP 1 LAST HDL_TAP TRUE
J 0
(-2300 1775);
DISPLAY 1.446809 (-2300 1775);
PAINT GREEN (-2300 1775);
DISPLAY INVISIBLE (-2300 1775);
FORCEPROP 1 LAST PATH I114
J 0
(-2627 1900);
DISPLAY 0.872340 (-2627 1900);
PAINT GREEN (-2627 1900);
DISPLAY INVISIBLE (-2627 1900);
FORCEADD TAP..1
(-2625 3000);
FORCEPROP 3 LASTPIN (-2675 3000) SIG_NAME UPI_CPU1_CPU0_P1P1_DN<6>
J 0
(-2665 3010);
DISPLAY 0.659574 (-2665 3010);
PAINT MONO (-2665 3010);
DISPLAY INVISIBLE (-2665 3010);
FORCEPROP 1 LASTPIN (-2675 3000) BN 6
J 0
(-2687 3008);
DISPLAY 0.617021 (-2687 3008);
PAINT GREEN (-2687 3008);
FORCEPROP 2 LAST CDS_LIB mstr_standard
J 0
(-2625 3000);
PAINT MONO (-2625 3000);
DISPLAY INVISIBLE (-2625 3000);
FORCEPROP 1 LAST BODY_TYPE PLUMBING
J 0
(-2625 3050);
DISPLAY 1.446809 (-2625 3050);
PAINT GREEN (-2625 3050);
DISPLAY INVISIBLE (-2625 3050);
FORCEPROP 1 LAST HDL_TAP TRUE
J 0
(-2300 2875);
DISPLAY 1.446809 (-2300 2875);
PAINT GREEN (-2300 2875);
DISPLAY INVISIBLE (-2300 2875);
FORCEPROP 1 LAST PATH I115
J 0
(-2627 3000);
DISPLAY 0.872340 (-2627 3000);
PAINT GREEN (-2627 3000);
DISPLAY INVISIBLE (-2627 3000);
FORCEADD TAP..1
(-2625 3050);
FORCEPROP 3 LASTPIN (-2675 3050) SIG_NAME UPI_CPU1_CPU0_P1P1_DN<7>
J 0
(-2665 3060);
DISPLAY 0.659574 (-2665 3060);
PAINT MONO (-2665 3060);
DISPLAY INVISIBLE (-2665 3060);
FORCEPROP 1 LASTPIN (-2675 3050) BN 7
J 0
(-2687 3058);
DISPLAY 0.617021 (-2687 3058);
PAINT GREEN (-2687 3058);
FORCEPROP 2 LAST CDS_LIB mstr_standard
J 0
(-2625 3050);
PAINT MONO (-2625 3050);
DISPLAY INVISIBLE (-2625 3050);
FORCEPROP 1 LAST BODY_TYPE PLUMBING
J 0
(-2625 3100);
DISPLAY 1.446809 (-2625 3100);
PAINT GREEN (-2625 3100);
DISPLAY INVISIBLE (-2625 3100);
FORCEPROP 1 LAST HDL_TAP TRUE
J 0
(-2300 2925);
DISPLAY 1.446809 (-2300 2925);
PAINT GREEN (-2300 2925);
DISPLAY INVISIBLE (-2300 2925);
FORCEPROP 1 LAST PATH I116
J 0
(-2627 3050);
DISPLAY 0.872340 (-2627 3050);
PAINT GREEN (-2627 3050);
DISPLAY INVISIBLE (-2627 3050);
FORCEADD TAP..1
(-2625 3100);
FORCEPROP 3 LASTPIN (-2675 3100) SIG_NAME UPI_CPU1_CPU0_P1P1_DN<8>
J 0
(-2665 3110);
DISPLAY 0.659574 (-2665 3110);
PAINT MONO (-2665 3110);
DISPLAY INVISIBLE (-2665 3110);
FORCEPROP 1 LASTPIN (-2675 3100) BN 8
J 0
(-2687 3108);
DISPLAY 0.617021 (-2687 3108);
PAINT GREEN (-2687 3108);
FORCEPROP 2 LAST CDS_LIB mstr_standard
J 0
(-2625 3100);
PAINT MONO (-2625 3100);
DISPLAY INVISIBLE (-2625 3100);
FORCEPROP 1 LAST BODY_TYPE PLUMBING
J 0
(-2625 3150);
DISPLAY 1.446809 (-2625 3150);
PAINT GREEN (-2625 3150);
DISPLAY INVISIBLE (-2625 3150);
FORCEPROP 1 LAST HDL_TAP TRUE
J 0
(-2300 2975);
DISPLAY 1.446809 (-2300 2975);
PAINT GREEN (-2300 2975);
DISPLAY INVISIBLE (-2300 2975);
FORCEPROP 1 LAST PATH I117
J 0
(-2627 3100);
DISPLAY 0.872340 (-2627 3100);
PAINT GREEN (-2627 3100);
DISPLAY INVISIBLE (-2627 3100);
FORCEADD TAP..1
(-2625 2100);
FORCEPROP 3 LASTPIN (-2675 2100) SIG_NAME UPI_CPU1_CPU0_P1P1_DN<9>
J 0
(-2665 2110);
DISPLAY 0.659574 (-2665 2110);
PAINT MONO (-2665 2110);
DISPLAY INVISIBLE (-2665 2110);
FORCEPROP 1 LASTPIN (-2675 2100) BN 9
J 0
(-2687 2108);
DISPLAY 0.617021 (-2687 2108);
PAINT GREEN (-2687 2108);
FORCEPROP 2 LAST CDS_LIB mstr_standard
J 0
(-2625 2100);
PAINT MONO (-2625 2100);
DISPLAY INVISIBLE (-2625 2100);
FORCEPROP 1 LAST BODY_TYPE PLUMBING
J 0
(-2625 2150);
DISPLAY 1.446809 (-2625 2150);
PAINT GREEN (-2625 2150);
DISPLAY INVISIBLE (-2625 2150);
FORCEPROP 1 LAST HDL_TAP TRUE
J 0
(-2300 1975);
DISPLAY 1.446809 (-2300 1975);
PAINT GREEN (-2300 1975);
DISPLAY INVISIBLE (-2300 1975);
FORCEPROP 1 LAST PATH I118
J 0
(-2627 2100);
DISPLAY 0.872340 (-2627 2100);
PAINT GREEN (-2627 2100);
DISPLAY INVISIBLE (-2627 2100);
FORCEADD TAP..1
(-2625 3250);
FORCEPROP 3 LASTPIN (-2675 3250) SIG_NAME UPI_CPU1_CPU0_P1P1_DN<11>
J 0
(-2665 3260);
DISPLAY 0.659574 (-2665 3260);
PAINT MONO (-2665 3260);
DISPLAY INVISIBLE (-2665 3260);
FORCEPROP 1 LASTPIN (-2675 3250) BN 11
J 0
(-2687 3258);
DISPLAY 0.617021 (-2687 3258);
PAINT GREEN (-2687 3258);
FORCEPROP 2 LAST CDS_LIB mstr_standard
J 0
(-2625 3250);
PAINT MONO (-2625 3250);
DISPLAY INVISIBLE (-2625 3250);
FORCEPROP 1 LAST BODY_TYPE PLUMBING
J 0
(-2625 3300);
DISPLAY 1.446809 (-2625 3300);
PAINT GREEN (-2625 3300);
DISPLAY INVISIBLE (-2625 3300);
FORCEPROP 1 LAST HDL_TAP TRUE
J 0
(-2300 3125);
DISPLAY 1.446809 (-2300 3125);
PAINT GREEN (-2300 3125);
DISPLAY INVISIBLE (-2300 3125);
FORCEPROP 1 LAST PATH I119
J 0
(-2627 3250);
DISPLAY 0.872340 (-2627 3250);
PAINT GREEN (-2627 3250);
DISPLAY INVISIBLE (-2627 3250);
FORCEADD TAP..1
(-2625 2300);
FORCEPROP 3 LASTPIN (-2675 2300) SIG_NAME UPI_CPU1_CPU0_P1P1_DN<13>
J 0
(-2665 2310);
DISPLAY 0.659574 (-2665 2310);
PAINT MONO (-2665 2310);
DISPLAY INVISIBLE (-2665 2310);
FORCEPROP 1 LASTPIN (-2675 2300) BN 13
J 0
(-2687 2308);
DISPLAY 0.617021 (-2687 2308);
PAINT GREEN (-2687 2308);
FORCEPROP 2 LAST CDS_LIB mstr_standard
J 0
(-2625 2300);
PAINT MONO (-2625 2300);
DISPLAY INVISIBLE (-2625 2300);
FORCEPROP 1 LAST BODY_TYPE PLUMBING
J 0
(-2625 2350);
DISPLAY 1.446809 (-2625 2350);
PAINT GREEN (-2625 2350);
DISPLAY INVISIBLE (-2625 2350);
FORCEPROP 1 LAST HDL_TAP TRUE
J 0
(-2300 2175);
DISPLAY 1.446809 (-2300 2175);
PAINT GREEN (-2300 2175);
DISPLAY INVISIBLE (-2300 2175);
FORCEPROP 1 LAST PATH I120
J 0
(-2627 2300);
DISPLAY 0.872340 (-2627 2300);
PAINT GREEN (-2627 2300);
DISPLAY INVISIBLE (-2627 2300);
FORCEADD TAP..1
(-2625 2350);
FORCEPROP 3 LASTPIN (-2675 2350) SIG_NAME UPI_CPU1_CPU0_P1P1_DN<14>
J 0
(-2665 2360);
DISPLAY 0.659574 (-2665 2360);
PAINT MONO (-2665 2360);
DISPLAY INVISIBLE (-2665 2360);
FORCEPROP 1 LASTPIN (-2675 2350) BN 14
J 0
(-2687 2358);
DISPLAY 0.617021 (-2687 2358);
PAINT GREEN (-2687 2358);
FORCEPROP 2 LAST CDS_LIB mstr_standard
J 0
(-2625 2350);
PAINT MONO (-2625 2350);
DISPLAY INVISIBLE (-2625 2350);
FORCEPROP 1 LAST BODY_TYPE PLUMBING
J 0
(-2625 2400);
DISPLAY 1.446809 (-2625 2400);
PAINT GREEN (-2625 2400);
DISPLAY INVISIBLE (-2625 2400);
FORCEPROP 1 LAST HDL_TAP TRUE
J 0
(-2300 2225);
DISPLAY 1.446809 (-2300 2225);
PAINT GREEN (-2300 2225);
DISPLAY INVISIBLE (-2300 2225);
FORCEPROP 1 LAST PATH I121
J 0
(-2627 2350);
DISPLAY 0.872340 (-2627 2350);
PAINT GREEN (-2627 2350);
DISPLAY INVISIBLE (-2627 2350);
FORCEADD TAP..1
(-2625 2400);
FORCEPROP 3 LASTPIN (-2675 2400) SIG_NAME UPI_CPU1_CPU0_P1P1_DN<15>
J 0
(-2665 2410);
DISPLAY 0.659574 (-2665 2410);
PAINT MONO (-2665 2410);
DISPLAY INVISIBLE (-2665 2410);
FORCEPROP 1 LASTPIN (-2675 2400) BN 15
J 0
(-2687 2408);
DISPLAY 0.617021 (-2687 2408);
PAINT GREEN (-2687 2408);
FORCEPROP 2 LAST CDS_LIB mstr_standard
J 0
(-2625 2400);
PAINT MONO (-2625 2400);
DISPLAY INVISIBLE (-2625 2400);
FORCEPROP 1 LAST BODY_TYPE PLUMBING
J 0
(-2625 2450);
DISPLAY 1.446809 (-2625 2450);
PAINT GREEN (-2625 2450);
DISPLAY INVISIBLE (-2625 2450);
FORCEPROP 1 LAST HDL_TAP TRUE
J 0
(-2300 2275);
DISPLAY 1.446809 (-2300 2275);
PAINT GREEN (-2300 2275);
DISPLAY INVISIBLE (-2300 2275);
FORCEPROP 1 LAST PATH I122
J 0
(-2627 2400);
DISPLAY 0.872340 (-2627 2400);
PAINT GREEN (-2627 2400);
DISPLAY INVISIBLE (-2627 2400);
FORCEADD TAP..1
(-2625 3600);
FORCEPROP 3 LASTPIN (-2675 3600) SIG_NAME UPI_CPU1_CPU0_P1P1_DN<18>
J 0
(-2665 3610);
DISPLAY 0.659574 (-2665 3610);
PAINT MONO (-2665 3610);
DISPLAY INVISIBLE (-2665 3610);
FORCEPROP 1 LASTPIN (-2675 3600) BN 18
J 0
(-2687 3608);
DISPLAY 0.617021 (-2687 3608);
PAINT GREEN (-2687 3608);
FORCEPROP 2 LAST CDS_LIB mstr_standard
J 0
(-2625 3600);
PAINT MONO (-2625 3600);
DISPLAY INVISIBLE (-2625 3600);
FORCEPROP 1 LAST BODY_TYPE PLUMBING
J 0
(-2625 3650);
DISPLAY 1.446809 (-2625 3650);
PAINT GREEN (-2625 3650);
DISPLAY INVISIBLE (-2625 3650);
FORCEPROP 1 LAST HDL_TAP TRUE
J 0
(-2300 3475);
DISPLAY 1.446809 (-2300 3475);
PAINT GREEN (-2300 3475);
DISPLAY INVISIBLE (-2300 3475);
FORCEPROP 1 LAST PATH I123
J 0
(-2627 3600);
DISPLAY 0.872340 (-2627 3600);
PAINT GREEN (-2627 3600);
DISPLAY INVISIBLE (-2627 3600);
FORCEADD TAP..1
(-2625 3650);
FORCEPROP 3 LASTPIN (-2675 3650) SIG_NAME UPI_CPU1_CPU0_P1P1_DN<19>
J 0
(-2665 3660);
DISPLAY 0.659574 (-2665 3660);
PAINT MONO (-2665 3660);
DISPLAY INVISIBLE (-2665 3660);
FORCEPROP 1 LASTPIN (-2675 3650) BN 19
J 0
(-2687 3658);
DISPLAY 0.617021 (-2687 3658);
PAINT GREEN (-2687 3658);
FORCEPROP 2 LAST CDS_LIB mstr_standard
J 2
(-2625 3650);
PAINT MONO (-2625 3650);
DISPLAY INVISIBLE (-2625 3650);
FORCEPROP 1 LAST BODY_TYPE PLUMBING
J 0
(-2625 3700);
DISPLAY 1.446809 (-2625 3700);
PAINT GREEN (-2625 3700);
DISPLAY INVISIBLE (-2625 3700);
FORCEPROP 1 LAST HDL_TAP TRUE
J 0
(-2300 3525);
DISPLAY 1.446809 (-2300 3525);
PAINT GREEN (-2300 3525);
DISPLAY INVISIBLE (-2300 3525);
FORCEPROP 1 LAST PATH I124
J 0
(-2627 3650);
DISPLAY 0.872340 (-2627 3650);
PAINT GREEN (-2627 3650);
DISPLAY INVISIBLE (-2627 3650);
FORCEADD SKX_EXT_B..14
(-4100 2650);
FORCEPROP 1 LAST LOCATION U2D1
J 0
(-4850 3900);
DISPLAY 0.617021 (-4850 3900);
PAINT AQUA (-4850 3900);
FORCEPROP 1 LAST PART_NUMBER TBD
J 0
(-4850 1450);
DISPLAY 0.617021 (-4850 1450);
PAINT BLUE (-4850 1450);
FORCEPROP 1 LAST MATERIAL IC
J 0
(-4850 3850);
DISPLAY 0.617021 (-4850 3850);
PAINT SKYBLUE (-4850 3850);
FORCEPROP 2 LASTPIN (-3300 3650) $PN K21
J 0
(-3290 3660);
DISPLAY 0.617021 (-3290 3660);
PAINT ORANGE (-3290 3660);
FORCEPROP 2 LASTPIN (-3300 3600) $PN G20
J 0
(-3290 3610);
DISPLAY 0.617021 (-3290 3610);
PAINT ORANGE (-3290 3610);
FORCEPROP 2 LASTPIN (-3300 3550) $PN H19
J 0
(-3290 3560);
DISPLAY 0.617021 (-3290 3560);
PAINT ORANGE (-3290 3560);
FORCEPROP 2 LASTPIN (-3300 3500) $PN J18
J 0
(-3290 3510);
DISPLAY 0.617021 (-3290 3510);
PAINT ORANGE (-3290 3510);
FORCEPROP 2 LASTPIN (-3300 3450) $PN L18
J 0
(-3290 3460);
DISPLAY 0.617021 (-3290 3460);
PAINT ORANGE (-3290 3460);
FORCEPROP 2 LASTPIN (-3300 3400) $PN G16
J 0
(-3290 3410);
DISPLAY 0.617021 (-3290 3410);
PAINT ORANGE (-3290 3410);
FORCEPROP 2 LASTPIN (-3300 3350) $PN H15
J 0
(-3290 3360);
DISPLAY 0.617021 (-3290 3360);
PAINT ORANGE (-3290 3360);
FORCEPROP 2 LASTPIN (-3300 3300) $PN E14
J 0
(-3290 3310);
DISPLAY 0.617021 (-3290 3310);
PAINT ORANGE (-3290 3310);
FORCEPROP 2 LASTPIN (-3300 3250) $PN F13
J 0
(-3290 3260);
DISPLAY 0.617021 (-3290 3260);
PAINT ORANGE (-3290 3260);
FORCEPROP 2 LASTPIN (-3300 3200) $PN G12
J 0
(-3290 3210);
DISPLAY 0.617021 (-3290 3210);
PAINT ORANGE (-3290 3210);
FORCEPROP 2 LASTPIN (-3300 3150) $PN H9
J 0
(-3290 3160);
DISPLAY 0.617021 (-3290 3160);
PAINT ORANGE (-3290 3160);
FORCEPROP 2 LASTPIN (-3300 3100) $PN E10
J 0
(-3290 3110);
DISPLAY 0.617021 (-3290 3110);
PAINT ORANGE (-3290 3110);
FORCEPROP 2 LASTPIN (-3300 3050) $PN F9
J 0
(-3290 3060);
DISPLAY 0.617021 (-3290 3060);
PAINT ORANGE (-3290 3060);
FORCEPROP 2 LASTPIN (-3300 3000) $PN J8
J 0
(-3290 3010);
DISPLAY 0.617021 (-3290 3010);
PAINT ORANGE (-3290 3010);
FORCEPROP 2 LASTPIN (-3300 2950) $PN K7
J 0
(-3290 2960);
DISPLAY 0.617021 (-3290 2960);
PAINT ORANGE (-3290 2960);
FORCEPROP 2 LASTPIN (-3300 2900) $PN F7
J 0
(-3290 2910);
DISPLAY 0.617021 (-3290 2910);
PAINT ORANGE (-3290 2910);
FORCEPROP 2 LASTPIN (-3300 2850) $PN H5
J 0
(-3290 2860);
DISPLAY 0.617021 (-3290 2860);
PAINT ORANGE (-3290 2860);
FORCEPROP 2 LASTPIN (-3300 2800) $PN M5
J 0
(-3290 2810);
DISPLAY 0.617021 (-3290 2810);
PAINT ORANGE (-3290 2810);
FORCEPROP 2 LASTPIN (-3300 2750) $PN K3
J 0
(-3290 2760);
DISPLAY 0.617021 (-3290 2760);
PAINT ORANGE (-3290 2760);
FORCEPROP 2 LASTPIN (-3300 2700) $PN P3
J 0
(-3290 2710);
DISPLAY 0.617021 (-3290 2710);
PAINT ORANGE (-3290 2710);
FORCEPROP 2 LASTPIN (-3300 2600) $PN H21
J 0
(-3290 2610);
DISPLAY 0.617021 (-3290 2610);
PAINT ORANGE (-3290 2610);
FORCEPROP 2 LASTPIN (-3300 2550) $PN F21
J 0
(-3290 2560);
DISPLAY 0.617021 (-3290 2560);
PAINT ORANGE (-3290 2560);
FORCEPROP 2 LASTPIN (-3300 2500) $PN J20
J 0
(-3290 2510);
DISPLAY 0.617021 (-3290 2510);
PAINT ORANGE (-3290 2510);
FORCEPROP 2 LASTPIN (-3300 2450) $PN G18
J 0
(-3290 2460);
DISPLAY 0.617021 (-3290 2460);
PAINT ORANGE (-3290 2460);
FORCEPROP 2 LASTPIN (-3300 2400) $PN K19
J 0
(-3290 2410);
DISPLAY 0.617021 (-3290 2410);
PAINT ORANGE (-3290 2410);
FORCEPROP 2 LASTPIN (-3300 2350) $PN H17
J 0
(-3290 2360);
DISPLAY 0.617021 (-3290 2360);
PAINT ORANGE (-3290 2360);
FORCEPROP 2 LASTPIN (-3300 2300) $PN F15
J 0
(-3290 2310);
DISPLAY 0.617021 (-3290 2310);
PAINT ORANGE (-3290 2310);
FORCEPROP 2 LASTPIN (-3300 2250) $PN D15
J 0
(-3290 2260);
DISPLAY 0.617021 (-3290 2260);
PAINT ORANGE (-3290 2260);
FORCEPROP 2 LASTPIN (-3300 2200) $PN G14
J 0
(-3290 2210);
DISPLAY 0.617021 (-3290 2210);
PAINT ORANGE (-3290 2210);
FORCEPROP 2 LASTPIN (-3300 2150) $PN E12
J 0
(-3290 2160);
DISPLAY 0.617021 (-3290 2160);
PAINT ORANGE (-3290 2160);
FORCEPROP 2 LASTPIN (-3300 2100) $PN G10
J 0
(-3290 2110);
DISPLAY 0.617021 (-3290 2110);
PAINT ORANGE (-3290 2110);
FORCEPROP 2 LASTPIN (-3300 2050) $PN F11
J 0
(-3290 2060);
DISPLAY 0.617021 (-3290 2060);
PAINT ORANGE (-3290 2060);
FORCEPROP 2 LASTPIN (-3300 2000) $PN D9
J 0
(-3290 2010);
DISPLAY 0.617021 (-3290 2010);
PAINT ORANGE (-3290 2010);
FORCEPROP 2 LASTPIN (-3300 1950) $PN K9
J 0
(-3290 1960);
DISPLAY 0.617021 (-3290 1960);
PAINT ORANGE (-3290 1960);
FORCEPROP 2 LASTPIN (-3300 1900) $PN H7
J 0
(-3290 1910);
DISPLAY 0.617021 (-3290 1910);
PAINT ORANGE (-3290 1910);
FORCEPROP 2 LASTPIN (-3300 1850) $PN G6
J 0
(-3290 1860);
DISPLAY 0.617021 (-3290 1860);
PAINT ORANGE (-3290 1860);
FORCEPROP 2 LASTPIN (-3300 1800) $PN J6
J 0
(-3290 1810);
DISPLAY 0.617021 (-3290 1810);
PAINT ORANGE (-3290 1810);
FORCEPROP 2 LASTPIN (-3300 1750) $PN K5
J 0
(-3290 1760);
DISPLAY 0.617021 (-3290 1760);
PAINT ORANGE (-3290 1760);
FORCEPROP 2 LASTPIN (-3300 1700) $PN L4
J 0
(-3290 1710);
DISPLAY 0.617021 (-3290 1710);
PAINT ORANGE (-3290 1710);
FORCEPROP 2 LASTPIN (-3300 1650) $PN M3
J 0
(-3290 1660);
DISPLAY 0.617021 (-3290 1660);
PAINT ORANGE (-3290 1660);
FORCEPROP 2 LASTPIN (-4900 3650) $PN AA20
J 2
(-4910 3660);
DISPLAY 0.617021 (-4910 3660);
PAINT ORANGE (-4910 3660);
FORCEPROP 2 LASTPIN (-4900 3600) $PN W20
J 2
(-4910 3610);
DISPLAY 0.617021 (-4910 3610);
PAINT ORANGE (-4910 3610);
FORCEPROP 2 LASTPIN (-4900 3550) $PN Y19
J 2
(-4910 3560);
DISPLAY 0.617021 (-4910 3560);
PAINT ORANGE (-4910 3560);
FORCEPROP 2 LASTPIN (-4900 3500) $PN T21
J 2
(-4910 3510);
DISPLAY 0.617021 (-4910 3510);
PAINT ORANGE (-4910 3510);
FORCEPROP 2 LASTPIN (-4900 3450) $PN T19
J 2
(-4910 3460);
DISPLAY 0.617021 (-4910 3460);
PAINT ORANGE (-4910 3460);
FORCEPROP 2 LASTPIN (-4900 3400) $PN P19
J 2
(-4910 3410);
DISPLAY 0.617021 (-4910 3410);
PAINT ORANGE (-4910 3410);
FORCEPROP 2 LASTPIN (-4900 3350) $PN V17
J 2
(-4910 3360);
DISPLAY 0.617021 (-4910 3360);
PAINT ORANGE (-4910 3360);
FORCEPROP 2 LASTPIN (-4900 3300) $PN W16
J 2
(-4910 3310);
DISPLAY 0.617021 (-4910 3310);
PAINT ORANGE (-4910 3310);
FORCEPROP 2 LASTPIN (-4900 3250) $PN N16
J 2
(-4910 3260);
DISPLAY 0.617021 (-4910 3260);
PAINT ORANGE (-4910 3260);
FORCEPROP 2 LASTPIN (-4900 3200) $PN T15
J 2
(-4910 3210);
DISPLAY 0.617021 (-4910 3210);
PAINT ORANGE (-4910 3210);
FORCEPROP 2 LASTPIN (-4900 3150) $PN P13
J 2
(-4910 3160);
DISPLAY 0.617021 (-4910 3160);
PAINT ORANGE (-4910 3160);
FORCEPROP 2 LASTPIN (-4900 3100) $PN M13
J 2
(-4910 3110);
DISPLAY 0.617021 (-4910 3110);
PAINT ORANGE (-4910 3110);
FORCEPROP 2 LASTPIN (-4900 3050) $PN N12
J 2
(-4910 3060);
DISPLAY 0.617021 (-4910 3060);
PAINT ORANGE (-4910 3060);
FORCEPROP 2 LASTPIN (-4900 2950) $PN U10
J 2
(-4910 2960);
DISPLAY 0.617021 (-4910 2960);
PAINT ORANGE (-4910 2960);
FORCEPROP 2 LASTPIN (-4900 2900) $PN N10
J 2
(-4910 2910);
DISPLAY 0.617021 (-4910 2910);
PAINT ORANGE (-4910 2910);
FORCEPROP 2 LASTPIN (-4900 2850) $PN R8
J 2
(-4910 2860);
DISPLAY 0.617021 (-4910 2860);
PAINT ORANGE (-4910 2860);
FORCEPROP 2 LASTPIN (-4900 2800) $PN U8
J 2
(-4910 2810);
DISPLAY 0.617021 (-4910 2810);
PAINT ORANGE (-4910 2810);
FORCEPROP 2 LASTPIN (-4900 2750) $PN T7
J 2
(-4910 2760);
DISPLAY 0.617021 (-4910 2760);
PAINT ORANGE (-4910 2760);
FORCEPROP 2 LASTPIN (-4900 2700) $PN R6
J 2
(-4910 2710);
DISPLAY 0.617021 (-4910 2710);
PAINT ORANGE (-4910 2710);
FORCEPROP 2 LASTPIN (-4900 2600) $PN AB19
J 2
(-4910 2610);
DISPLAY 0.617021 (-4910 2610);
PAINT ORANGE (-4910 2610);
FORCEPROP 2 LASTPIN (-4900 2550) $PN Y21
J 2
(-4910 2560);
DISPLAY 0.617021 (-4910 2560);
PAINT ORANGE (-4910 2560);
FORCEPROP 2 LASTPIN (-4900 2500) $PN V19
J 2
(-4910 2510);
DISPLAY 0.617021 (-4910 2510);
PAINT ORANGE (-4910 2510);
FORCEPROP 2 LASTPIN (-4900 2450) $PN P21
J 2
(-4910 2460);
DISPLAY 0.617021 (-4910 2460);
PAINT ORANGE (-4910 2460);
FORCEPROP 2 LASTPIN (-4900 2400) $PN U18
J 2
(-4910 2410);
DISPLAY 0.617021 (-4910 2410);
PAINT ORANGE (-4910 2410);
FORCEPROP 2 LASTPIN (-4900 2350) $PN R20
J 2
(-4910 2360);
DISPLAY 0.617021 (-4910 2360);
PAINT ORANGE (-4910 2360);
FORCEPROP 2 LASTPIN (-4900 2300) $PN W18
J 2
(-4910 2310);
DISPLAY 0.617021 (-4910 2310);
PAINT ORANGE (-4910 2310);
FORCEPROP 2 LASTPIN (-4900 2250) $PN U16
J 2
(-4910 2260);
DISPLAY 0.617021 (-4910 2260);
PAINT ORANGE (-4910 2260);
FORCEPROP 2 LASTPIN (-4900 2200) $PN P17
J 2
(-4910 2210);
DISPLAY 0.617021 (-4910 2210);
PAINT ORANGE (-4910 2210);
FORCEPROP 2 LASTPIN (-4900 2150) $PN R16
J 2
(-4910 2160);
DISPLAY 0.617021 (-4910 2160);
PAINT ORANGE (-4910 2160);
FORCEPROP 2 LASTPIN (-4900 2100) $PN R12
J 2
(-4910 2110);
DISPLAY 0.617021 (-4910 2110);
PAINT ORANGE (-4910 2110);
FORCEPROP 2 LASTPIN (-4900 2050) $PN N14
J 2
(-4910 2060);
DISPLAY 0.617021 (-4910 2060);
PAINT ORANGE (-4910 2060);
FORCEPROP 2 LASTPIN (-4900 2000) $PN L12
J 2
(-4910 2010);
DISPLAY 0.617021 (-4910 2010);
PAINT ORANGE (-4910 2010);
FORCEPROP 2 LASTPIN (-4900 1950) $PN U12
J 2
(-4910 1960);
DISPLAY 0.617021 (-4910 1960);
PAINT ORANGE (-4910 1960);
FORCEPROP 2 LASTPIN (-4900 1900) $PN R10
J 2
(-4910 1910);
DISPLAY 0.617021 (-4910 1910);
PAINT ORANGE (-4910 1910);
FORCEPROP 2 LASTPIN (-4900 1850) $PN P9
J 2
(-4910 1860);
DISPLAY 0.617021 (-4910 1860);
PAINT ORANGE (-4910 1860);
FORCEPROP 2 LASTPIN (-4900 1800) $PN T9
J 2
(-4910 1810);
DISPLAY 0.617021 (-4910 1810);
PAINT ORANGE (-4910 1810);
FORCEPROP 2 LASTPIN (-4900 1750) $PN V7
J 2
(-4910 1760);
DISPLAY 0.617021 (-4910 1760);
PAINT ORANGE (-4910 1760);
FORCEPROP 2 LASTPIN (-4900 1700) $PN P7
J 2
(-4910 1710);
DISPLAY 0.617021 (-4910 1710);
PAINT ORANGE (-4910 1710);
FORCEPROP 2 LASTPIN (-4900 1650) $PN T5
J 2
(-4910 1660);
DISPLAY 0.617021 (-4910 1660);
PAINT ORANGE (-4910 1660);
FORCEPROP 2 LASTPIN (-4900 3000) $PN T11
J 2
(-4910 3010);
DISPLAY 0.617021 (-4910 3010);
PAINT ORANGE (-4910 3010);
FORCEPROP 1 LAST PACK_TYPE BGA1
J 0
(-4850 3950);
PAINT SKYBLUE (-4850 3950);
DISPLAY INVISIBLE (-4850 3950);
FORCEPROP 2 LAST SEC_TYPE BGA1
J 0
(-4850 3950);
DISPLAY 1.021277 (-4850 3950);
PAINT ORANGE (-4850 3950);
DISPLAY INVISIBLE (-4850 3950);
FORCEPROP 2 LAST CDS_LIB chpset_lib
J 0
(-4100 2650);
PAINT ORANGE (-4100 2650);
DISPLAY INVISIBLE (-4100 2650);
FORCEPROP 2 LAST SEC 14
J 0
(-4850 3950);
DISPLAY 0.680851 (-4850 3950);
PAINT MONO (-4850 3950);
DISPLAY INVISIBLE (-4850 3950);
FORCEPROP 2 LAST CDS_LOCATION U2D1
J 0
(-4850 3900);
DISPLAY 0.617021 (-4850 3900);
PAINT AQUA (-4850 3900);
DISPLAY INVISIBLE (-4850 3900);
FORCEPROP 1 LAST PATH I125
J 0
(-4100 3850);
PAINT GREEN (-4100 3850);
DISPLAY INVISIBLE (-4100 3850);
FORCEADD TAP..1
R 2
(-5725 2100);
FORCEPROP 3 LASTPIN (-5675 2100) SIG_NAME UPI_CPU0_CPU1_P1P1_DN<9>
J 0
(-5665 2110);
DISPLAY 0.659574 (-5665 2110);
PAINT MONO (-5665 2110);
DISPLAY INVISIBLE (-5665 2110);
FORCEPROP 1 LASTPIN (-5675 2100) BN 9
J 2
(-5663 2108);
DISPLAY 0.617021 (-5663 2108);
PAINT GREEN (-5663 2108);
FORCEPROP 2 LAST CDS_LIB mstr_standard
J 0
(-5725 2100);
PAINT MONO (-5725 2100);
DISPLAY INVISIBLE (-5725 2100);
FORCEPROP 1 LAST BODY_TYPE PLUMBING
J 2
(-5725 2150);
DISPLAY 1.446809 (-5725 2150);
PAINT GREEN (-5725 2150);
DISPLAY INVISIBLE (-5725 2150);
FORCEPROP 1 LAST HDL_TAP TRUE
J 2
(-6050 1975);
DISPLAY 1.446809 (-6050 1975);
PAINT GREEN (-6050 1975);
DISPLAY INVISIBLE (-6050 1975);
FORCEPROP 1 LAST PATH I13
J 2
(-5723 2100);
DISPLAY 0.872340 (-5723 2100);
PAINT GREEN (-5723 2100);
DISPLAY INVISIBLE (-5723 2100);
FORCEADD TAP..1
R 2
(-5725 2150);
FORCEPROP 3 LASTPIN (-5675 2150) SIG_NAME UPI_CPU0_CPU1_P1P1_DN<10>
J 0
(-5665 2160);
DISPLAY 0.659574 (-5665 2160);
PAINT MONO (-5665 2160);
DISPLAY INVISIBLE (-5665 2160);
FORCEPROP 1 LASTPIN (-5675 2150) BN 10
J 2
(-5663 2158);
DISPLAY 0.617021 (-5663 2158);
PAINT GREEN (-5663 2158);
FORCEPROP 2 LAST CDS_LIB mstr_standard
J 0
(-5725 2150);
PAINT MONO (-5725 2150);
DISPLAY INVISIBLE (-5725 2150);
FORCEPROP 1 LAST BODY_TYPE PLUMBING
J 2
(-5725 2200);
DISPLAY 1.446809 (-5725 2200);
PAINT GREEN (-5725 2200);
DISPLAY INVISIBLE (-5725 2200);
FORCEPROP 1 LAST HDL_TAP TRUE
J 2
(-6050 2025);
DISPLAY 1.446809 (-6050 2025);
PAINT GREEN (-6050 2025);
DISPLAY INVISIBLE (-6050 2025);
FORCEPROP 1 LAST PATH I14
J 2
(-5723 2150);
DISPLAY 0.872340 (-5723 2150);
PAINT GREEN (-5723 2150);
DISPLAY INVISIBLE (-5723 2150);
FORCEADD TAP..1
R 2
(-5725 2350);
FORCEPROP 3 LASTPIN (-5675 2350) SIG_NAME UPI_CPU0_CPU1_P1P1_DN<14>
J 0
(-5665 2360);
DISPLAY 0.659574 (-5665 2360);
PAINT MONO (-5665 2360);
DISPLAY INVISIBLE (-5665 2360);
FORCEPROP 1 LASTPIN (-5675 2350) BN 14
J 2
(-5663 2358);
DISPLAY 0.617021 (-5663 2358);
PAINT GREEN (-5663 2358);
FORCEPROP 2 LAST CDS_LIB mstr_standard
J 0
(-5725 2350);
PAINT MONO (-5725 2350);
DISPLAY INVISIBLE (-5725 2350);
FORCEPROP 1 LAST BODY_TYPE PLUMBING
J 2
(-5725 2400);
DISPLAY 1.446809 (-5725 2400);
PAINT GREEN (-5725 2400);
DISPLAY INVISIBLE (-5725 2400);
FORCEPROP 1 LAST HDL_TAP TRUE
J 2
(-6050 2225);
DISPLAY 1.446809 (-6050 2225);
PAINT GREEN (-6050 2225);
DISPLAY INVISIBLE (-6050 2225);
FORCEPROP 1 LAST PATH I18
J 2
(-5723 2350);
DISPLAY 0.872340 (-5723 2350);
PAINT GREEN (-5723 2350);
DISPLAY INVISIBLE (-5723 2350);
FORCEADD OFFPAGE..1
(-6925 3800);
FORCEPROP 2 LAST $XR0 34 
J 0
(-7146 3800);
DISPLAY 0.638298 (-7146 3800);
PAINT MONO (-7146 3800);
FORCEPROP 2 LAST CDS_LIB mstr_standard
J 0
(-6925 3800);
PAINT MONO (-6925 3800);
DISPLAY INVISIBLE (-6925 3800);
FORCEPROP 1 LAST OFFPAGE TRUE
J 0
(-6600 3675);
DISPLAY 1.170213 (-6600 3675);
PAINT GREEN (-6600 3675);
DISPLAY INVISIBLE (-6600 3675);
FORCEPROP 1 LAST COMMENT_BODY TRUE
J 0
(-6800 3700);
DISPLAY 1.170213 (-6800 3700);
PAINT GREEN (-6800 3700);
DISPLAY INVISIBLE (-6800 3700);
FORCEPROP 2 LAST PATH I2
J 0
(-6875 3875);
DISPLAY 1.021277 (-6875 3875);
PAINT ORANGE (-6875 3875);
DISPLAY INVISIBLE (-6875 3875);
FORCEADD TAP..1
R 2
(-5725 2500);
FORCEPROP 3 LASTPIN (-5675 2500) SIG_NAME UPI_CPU0_CPU1_P1P1_DN<17>
J 0
(-5665 2510);
DISPLAY 0.659574 (-5665 2510);
PAINT MONO (-5665 2510);
DISPLAY INVISIBLE (-5665 2510);
FORCEPROP 1 LASTPIN (-5675 2500) BN 17
J 2
(-5663 2508);
DISPLAY 0.617021 (-5663 2508);
PAINT GREEN (-5663 2508);
FORCEPROP 2 LAST CDS_LIB mstr_standard
J 0
(-5725 2500);
PAINT MONO (-5725 2500);
DISPLAY INVISIBLE (-5725 2500);
FORCEPROP 1 LAST BODY_TYPE PLUMBING
J 2
(-5725 2550);
DISPLAY 1.446809 (-5725 2550);
PAINT GREEN (-5725 2550);
DISPLAY INVISIBLE (-5725 2550);
FORCEPROP 1 LAST HDL_TAP TRUE
J 2
(-6050 2375);
DISPLAY 1.446809 (-6050 2375);
PAINT GREEN (-6050 2375);
DISPLAY INVISIBLE (-6050 2375);
FORCEPROP 1 LAST PATH I21
J 2
(-5723 2500);
DISPLAY 0.872340 (-5723 2500);
PAINT GREEN (-5723 2500);
DISPLAY INVISIBLE (-5723 2500);
FORCEADD TAP..1
R 2
(-5725 3600);
FORCEPROP 3 LASTPIN (-5675 3600) SIG_NAME UPI_CPU0_CPU1_P1P1_DN<18>
J 0
(-5665 3610);
DISPLAY 0.659574 (-5665 3610);
PAINT MONO (-5665 3610);
DISPLAY INVISIBLE (-5665 3610);
FORCEPROP 1 LASTPIN (-5675 3600) BN 18
J 2
(-5663 3608);
DISPLAY 0.617021 (-5663 3608);
PAINT GREEN (-5663 3608);
FORCEPROP 2 LAST CDS_LIB mstr_standard
J 0
(-5725 3600);
PAINT MONO (-5725 3600);
DISPLAY INVISIBLE (-5725 3600);
FORCEPROP 1 LAST BODY_TYPE PLUMBING
J 2
(-5725 3650);
DISPLAY 1.446809 (-5725 3650);
PAINT GREEN (-5725 3650);
DISPLAY INVISIBLE (-5725 3650);
FORCEPROP 1 LAST HDL_TAP TRUE
J 2
(-6050 3475);
DISPLAY 1.446809 (-6050 3475);
PAINT GREEN (-6050 3475);
DISPLAY INVISIBLE (-6050 3475);
FORCEPROP 1 LAST PATH I22
J 2
(-5723 3600);
DISPLAY 0.872340 (-5723 3600);
PAINT GREEN (-5723 3600);
DISPLAY INVISIBLE (-5723 3600);
FORCEADD TAP..1
R 2
(-5275 2800);
FORCEPROP 3 LASTPIN (-5225 2800) SIG_NAME UPI_CPU0_CPU1_P1P1_DP<2>
J 0
(-5215 2810);
DISPLAY 0.659574 (-5215 2810);
PAINT MONO (-5215 2810);
DISPLAY INVISIBLE (-5215 2810);
FORCEPROP 1 LASTPIN (-5225 2800) BN 2
J 2
(-5213 2808);
DISPLAY 0.617021 (-5213 2808);
PAINT GREEN (-5213 2808);
FORCEPROP 2 LAST CDS_LIB mstr_standard
J 0
(-5275 2800);
PAINT MONO (-5275 2800);
DISPLAY INVISIBLE (-5275 2800);
FORCEPROP 1 LAST BODY_TYPE PLUMBING
J 2
(-5275 2850);
DISPLAY 1.446809 (-5275 2850);
PAINT GREEN (-5275 2850);
DISPLAY INVISIBLE (-5275 2850);
FORCEPROP 1 LAST HDL_TAP TRUE
J 2
(-5600 2675);
DISPLAY 1.446809 (-5600 2675);
PAINT GREEN (-5600 2675);
DISPLAY INVISIBLE (-5600 2675);
FORCEPROP 1 LAST PATH I26
J 2
(-5273 2800);
DISPLAY 0.872340 (-5273 2800);
PAINT GREEN (-5273 2800);
DISPLAY INVISIBLE (-5273 2800);
FORCEADD TAP..1
R 2
(-5275 2850);
FORCEPROP 3 LASTPIN (-5225 2850) SIG_NAME UPI_CPU0_CPU1_P1P1_DP<3>
J 0
(-5215 2860);
DISPLAY 0.659574 (-5215 2860);
PAINT MONO (-5215 2860);
DISPLAY INVISIBLE (-5215 2860);
FORCEPROP 1 LASTPIN (-5225 2850) BN 3
J 2
(-5213 2858);
DISPLAY 0.617021 (-5213 2858);
PAINT GREEN (-5213 2858);
FORCEPROP 2 LAST CDS_LIB mstr_standard
J 0
(-5275 2850);
PAINT MONO (-5275 2850);
DISPLAY INVISIBLE (-5275 2850);
FORCEPROP 1 LAST BODY_TYPE PLUMBING
J 2
(-5275 2900);
DISPLAY 1.446809 (-5275 2900);
PAINT GREEN (-5275 2900);
DISPLAY INVISIBLE (-5275 2900);
FORCEPROP 1 LAST HDL_TAP TRUE
J 2
(-5600 2725);
DISPLAY 1.446809 (-5600 2725);
PAINT GREEN (-5600 2725);
DISPLAY INVISIBLE (-5600 2725);
FORCEPROP 1 LAST PATH I27
J 2
(-5273 2850);
DISPLAY 0.872340 (-5273 2850);
PAINT GREEN (-5273 2850);
DISPLAY INVISIBLE (-5273 2850);
FORCEADD TAP..1
R 2
(-5275 2900);
FORCEPROP 3 LASTPIN (-5225 2900) SIG_NAME UPI_CPU0_CPU1_P1P1_DP<4>
J 0
(-5215 2910);
DISPLAY 0.659574 (-5215 2910);
PAINT MONO (-5215 2910);
DISPLAY INVISIBLE (-5215 2910);
FORCEPROP 1 LASTPIN (-5225 2900) BN 4
J 2
(-5213 2908);
DISPLAY 0.617021 (-5213 2908);
PAINT GREEN (-5213 2908);
FORCEPROP 2 LAST CDS_LIB mstr_standard
J 0
(-5275 2900);
PAINT MONO (-5275 2900);
DISPLAY INVISIBLE (-5275 2900);
FORCEPROP 1 LAST BODY_TYPE PLUMBING
J 2
(-5275 2950);
DISPLAY 1.446809 (-5275 2950);
PAINT GREEN (-5275 2950);
DISPLAY INVISIBLE (-5275 2950);
FORCEPROP 1 LAST HDL_TAP TRUE
J 2
(-5600 2775);
DISPLAY 1.446809 (-5600 2775);
PAINT GREEN (-5600 2775);
DISPLAY INVISIBLE (-5600 2775);
FORCEPROP 1 LAST PATH I28
J 2
(-5273 2900);
DISPLAY 0.872340 (-5273 2900);
PAINT GREEN (-5273 2900);
DISPLAY INVISIBLE (-5273 2900);
FORCEADD TAP..1
R 2
(-5275 2950);
FORCEPROP 3 LASTPIN (-5225 2950) SIG_NAME UPI_CPU0_CPU1_P1P1_DP<5>
J 0
(-5215 2960);
DISPLAY 0.659574 (-5215 2960);
PAINT MONO (-5215 2960);
DISPLAY INVISIBLE (-5215 2960);
FORCEPROP 1 LASTPIN (-5225 2950) BN 5
J 2
(-5213 2958);
DISPLAY 0.617021 (-5213 2958);
PAINT GREEN (-5213 2958);
FORCEPROP 2 LAST CDS_LIB mstr_standard
J 0
(-5275 2950);
PAINT MONO (-5275 2950);
DISPLAY INVISIBLE (-5275 2950);
FORCEPROP 1 LAST BODY_TYPE PLUMBING
J 2
(-5275 3000);
DISPLAY 1.446809 (-5275 3000);
PAINT GREEN (-5275 3000);
DISPLAY INVISIBLE (-5275 3000);
FORCEPROP 1 LAST HDL_TAP TRUE
J 2
(-5600 2825);
DISPLAY 1.446809 (-5600 2825);
PAINT GREEN (-5600 2825);
DISPLAY INVISIBLE (-5600 2825);
FORCEPROP 1 LAST PATH I29
J 2
(-5273 2950);
DISPLAY 0.872340 (-5273 2950);
PAINT GREEN (-5273 2950);
DISPLAY INVISIBLE (-5273 2950);
FORCEADD TAP..1
R 2
(-5275 3000);
FORCEPROP 3 LASTPIN (-5225 3000) SIG_NAME UPI_CPU0_CPU1_P1P1_DP<6>
J 0
(-5215 3010);
DISPLAY 0.659574 (-5215 3010);
PAINT MONO (-5215 3010);
DISPLAY INVISIBLE (-5215 3010);
FORCEPROP 1 LASTPIN (-5225 3000) BN 6
J 2
(-5213 3008);
DISPLAY 0.617021 (-5213 3008);
PAINT GREEN (-5213 3008);
FORCEPROP 2 LAST CDS_LIB mstr_standard
J 0
(-5275 3000);
PAINT MONO (-5275 3000);
DISPLAY INVISIBLE (-5275 3000);
FORCEPROP 1 LAST BODY_TYPE PLUMBING
J 2
(-5275 3050);
DISPLAY 1.446809 (-5275 3050);
PAINT GREEN (-5275 3050);
DISPLAY INVISIBLE (-5275 3050);
FORCEPROP 1 LAST HDL_TAP TRUE
J 2
(-5600 2875);
DISPLAY 1.446809 (-5600 2875);
PAINT GREEN (-5600 2875);
DISPLAY INVISIBLE (-5600 2875);
FORCEPROP 1 LAST PATH I30
J 2
(-5273 3000);
DISPLAY 0.872340 (-5273 3000);
PAINT GREEN (-5273 3000);
DISPLAY INVISIBLE (-5273 3000);
FORCEADD TAP..1
R 2
(-5275 3050);
FORCEPROP 3 LASTPIN (-5225 3050) SIG_NAME UPI_CPU0_CPU1_P1P1_DP<7>
J 0
(-5215 3060);
DISPLAY 0.659574 (-5215 3060);
PAINT MONO (-5215 3060);
DISPLAY INVISIBLE (-5215 3060);
FORCEPROP 1 LASTPIN (-5225 3050) BN 7
J 2
(-5213 3058);
DISPLAY 0.617021 (-5213 3058);
PAINT GREEN (-5213 3058);
FORCEPROP 2 LAST CDS_LIB mstr_standard
J 0
(-5275 3050);
PAINT MONO (-5275 3050);
DISPLAY INVISIBLE (-5275 3050);
FORCEPROP 1 LAST BODY_TYPE PLUMBING
J 2
(-5275 3100);
DISPLAY 1.446809 (-5275 3100);
PAINT GREEN (-5275 3100);
DISPLAY INVISIBLE (-5275 3100);
FORCEPROP 1 LAST HDL_TAP TRUE
J 2
(-5600 2925);
DISPLAY 1.446809 (-5600 2925);
PAINT GREEN (-5600 2925);
DISPLAY INVISIBLE (-5600 2925);
FORCEPROP 1 LAST PATH I31
J 2
(-5273 3050);
DISPLAY 0.872340 (-5273 3050);
PAINT GREEN (-5273 3050);
DISPLAY INVISIBLE (-5273 3050);
FORCEADD TAP..1
R 2
(-5275 2050);
FORCEPROP 3 LASTPIN (-5225 2050) SIG_NAME UPI_CPU0_CPU1_P1P1_DP<8>
J 0
(-5215 2060);
DISPLAY 0.659574 (-5215 2060);
PAINT MONO (-5215 2060);
DISPLAY INVISIBLE (-5215 2060);
FORCEPROP 1 LASTPIN (-5225 2050) BN 8
J 2
(-5213 2058);
DISPLAY 0.617021 (-5213 2058);
PAINT GREEN (-5213 2058);
FORCEPROP 2 LAST CDS_LIB mstr_standard
J 0
(-5275 2050);
PAINT MONO (-5275 2050);
DISPLAY INVISIBLE (-5275 2050);
FORCEPROP 1 LAST BODY_TYPE PLUMBING
J 2
(-5275 2100);
DISPLAY 1.446809 (-5275 2100);
PAINT GREEN (-5275 2100);
DISPLAY INVISIBLE (-5275 2100);
FORCEPROP 1 LAST HDL_TAP TRUE
J 2
(-5600 1925);
DISPLAY 1.446809 (-5600 1925);
PAINT GREEN (-5600 1925);
DISPLAY INVISIBLE (-5600 1925);
FORCEPROP 1 LAST PATH I32
J 2
(-5273 2050);
DISPLAY 0.872340 (-5273 2050);
PAINT GREEN (-5273 2050);
DISPLAY INVISIBLE (-5273 2050);
FORCEADD TAP..1
R 2
(-5275 3150);
FORCEPROP 3 LASTPIN (-5225 3150) SIG_NAME UPI_CPU0_CPU1_P1P1_DP<9>
J 0
(-5215 3160);
DISPLAY 0.659574 (-5215 3160);
PAINT MONO (-5215 3160);
DISPLAY INVISIBLE (-5215 3160);
FORCEPROP 1 LASTPIN (-5225 3150) BN 9
J 2
(-5213 3158);
DISPLAY 0.617021 (-5213 3158);
PAINT GREEN (-5213 3158);
FORCEPROP 2 LAST CDS_LIB mstr_standard
J 0
(-5275 3150);
PAINT MONO (-5275 3150);
DISPLAY INVISIBLE (-5275 3150);
FORCEPROP 1 LAST BODY_TYPE PLUMBING
J 2
(-5275 3200);
DISPLAY 1.446809 (-5275 3200);
PAINT GREEN (-5275 3200);
DISPLAY INVISIBLE (-5275 3200);
FORCEPROP 1 LAST HDL_TAP TRUE
J 2
(-5600 3025);
DISPLAY 1.446809 (-5600 3025);
PAINT GREEN (-5600 3025);
DISPLAY INVISIBLE (-5600 3025);
FORCEPROP 1 LAST PATH I33
J 2
(-5273 3150);
DISPLAY 0.872340 (-5273 3150);
PAINT GREEN (-5273 3150);
DISPLAY INVISIBLE (-5273 3150);
FORCEADD TAP..1
R 2
(-5275 3200);
FORCEPROP 3 LASTPIN (-5225 3200) SIG_NAME UPI_CPU0_CPU1_P1P1_DP<10>
J 0
(-5215 3210);
DISPLAY 0.659574 (-5215 3210);
PAINT MONO (-5215 3210);
DISPLAY INVISIBLE (-5215 3210);
FORCEPROP 1 LASTPIN (-5225 3200) BN 10
J 2
(-5213 3208);
DISPLAY 0.617021 (-5213 3208);
PAINT GREEN (-5213 3208);
FORCEPROP 2 LAST CDS_LIB mstr_standard
J 0
(-5275 3200);
PAINT MONO (-5275 3200);
DISPLAY INVISIBLE (-5275 3200);
FORCEPROP 1 LAST BODY_TYPE PLUMBING
J 2
(-5275 3250);
DISPLAY 1.446809 (-5275 3250);
PAINT GREEN (-5275 3250);
DISPLAY INVISIBLE (-5275 3250);
FORCEPROP 1 LAST HDL_TAP TRUE
J 2
(-5600 3075);
DISPLAY 1.446809 (-5600 3075);
PAINT GREEN (-5600 3075);
DISPLAY INVISIBLE (-5600 3075);
FORCEPROP 1 LAST PATH I34
J 2
(-5273 3200);
DISPLAY 0.872340 (-5273 3200);
PAINT GREEN (-5273 3200);
DISPLAY INVISIBLE (-5273 3200);
FORCEADD TAP..1
R 2
(-5275 2200);
FORCEPROP 3 LASTPIN (-5225 2200) SIG_NAME UPI_CPU0_CPU1_P1P1_DP<11>
J 0
(-5215 2210);
DISPLAY 0.659574 (-5215 2210);
PAINT MONO (-5215 2210);
DISPLAY INVISIBLE (-5215 2210);
FORCEPROP 1 LASTPIN (-5225 2200) BN 11
J 2
(-5213 2208);
DISPLAY 0.617021 (-5213 2208);
PAINT GREEN (-5213 2208);
FORCEPROP 2 LAST CDS_LIB mstr_standard
J 0
(-5275 2200);
PAINT MONO (-5275 2200);
DISPLAY INVISIBLE (-5275 2200);
FORCEPROP 1 LAST BODY_TYPE PLUMBING
J 2
(-5275 2250);
DISPLAY 1.446809 (-5275 2250);
PAINT GREEN (-5275 2250);
DISPLAY INVISIBLE (-5275 2250);
FORCEPROP 1 LAST HDL_TAP TRUE
J 2
(-5600 2075);
DISPLAY 1.446809 (-5600 2075);
PAINT GREEN (-5600 2075);
DISPLAY INVISIBLE (-5600 2075);
FORCEPROP 1 LAST PATH I35
J 2
(-5273 2200);
DISPLAY 0.872340 (-5273 2200);
PAINT GREEN (-5273 2200);
DISPLAY INVISIBLE (-5273 2200);
FORCEADD TAP..1
R 2
(-5275 2250);
FORCEPROP 3 LASTPIN (-5225 2250) SIG_NAME UPI_CPU0_CPU1_P1P1_DP<12>
J 0
(-5215 2260);
DISPLAY 0.659574 (-5215 2260);
PAINT MONO (-5215 2260);
DISPLAY INVISIBLE (-5215 2260);
FORCEPROP 1 LASTPIN (-5225 2250) BN 12
J 2
(-5213 2258);
DISPLAY 0.617021 (-5213 2258);
PAINT GREEN (-5213 2258);
FORCEPROP 2 LAST CDS_LIB mstr_standard
J 0
(-5275 2250);
PAINT MONO (-5275 2250);
DISPLAY INVISIBLE (-5275 2250);
FORCEPROP 1 LAST BODY_TYPE PLUMBING
J 2
(-5275 2300);
DISPLAY 1.446809 (-5275 2300);
PAINT GREEN (-5275 2300);
DISPLAY INVISIBLE (-5275 2300);
FORCEPROP 1 LAST HDL_TAP TRUE
J 2
(-5600 2125);
DISPLAY 1.446809 (-5600 2125);
PAINT GREEN (-5600 2125);
DISPLAY INVISIBLE (-5600 2125);
FORCEPROP 1 LAST PATH I36
J 2
(-5273 2250);
DISPLAY 0.872340 (-5273 2250);
PAINT GREEN (-5273 2250);
DISPLAY INVISIBLE (-5273 2250);
FORCEADD TAP..1
R 2
(-5275 2300);
FORCEPROP 3 LASTPIN (-5225 2300) SIG_NAME UPI_CPU0_CPU1_P1P1_DP<13>
J 0
(-5215 2310);
DISPLAY 0.659574 (-5215 2310);
PAINT MONO (-5215 2310);
DISPLAY INVISIBLE (-5215 2310);
FORCEPROP 1 LASTPIN (-5225 2300) BN 13
J 2
(-5213 2308);
DISPLAY 0.617021 (-5213 2308);
PAINT GREEN (-5213 2308);
FORCEPROP 2 LAST CDS_LIB mstr_standard
J 0
(-5275 2300);
PAINT MONO (-5275 2300);
DISPLAY INVISIBLE (-5275 2300);
FORCEPROP 1 LAST BODY_TYPE PLUMBING
J 2
(-5275 2350);
DISPLAY 1.446809 (-5275 2350);
PAINT GREEN (-5275 2350);
DISPLAY INVISIBLE (-5275 2350);
FORCEPROP 1 LAST HDL_TAP TRUE
J 2
(-5600 2175);
DISPLAY 1.446809 (-5600 2175);
PAINT GREEN (-5600 2175);
DISPLAY INVISIBLE (-5600 2175);
FORCEPROP 1 LAST PATH I37
J 2
(-5273 2300);
DISPLAY 0.872340 (-5273 2300);
PAINT GREEN (-5273 2300);
DISPLAY INVISIBLE (-5273 2300);
FORCEADD TAP..1
R 2
(-5275 3400);
FORCEPROP 3 LASTPIN (-5225 3400) SIG_NAME UPI_CPU0_CPU1_P1P1_DP<14>
J 0
(-5215 3410);
DISPLAY 0.659574 (-5215 3410);
PAINT MONO (-5215 3410);
DISPLAY INVISIBLE (-5215 3410);
FORCEPROP 1 LASTPIN (-5225 3400) BN 14
J 2
(-5213 3408);
DISPLAY 0.617021 (-5213 3408);
PAINT GREEN (-5213 3408);
FORCEPROP 2 LAST CDS_LIB mstr_standard
J 0
(-5275 3400);
PAINT MONO (-5275 3400);
DISPLAY INVISIBLE (-5275 3400);
FORCEPROP 1 LAST BODY_TYPE PLUMBING
J 2
(-5275 3450);
DISPLAY 1.446809 (-5275 3450);
PAINT GREEN (-5275 3450);
DISPLAY INVISIBLE (-5275 3450);
FORCEPROP 1 LAST HDL_TAP TRUE
J 2
(-5600 3275);
DISPLAY 1.446809 (-5600 3275);
PAINT GREEN (-5600 3275);
DISPLAY INVISIBLE (-5600 3275);
FORCEPROP 1 LAST PATH I38
J 2
(-5273 3400);
DISPLAY 0.872340 (-5273 3400);
PAINT GREEN (-5273 3400);
DISPLAY INVISIBLE (-5273 3400);
FORCEADD TAP..1
R 2
(-5275 3450);
FORCEPROP 3 LASTPIN (-5225 3450) SIG_NAME UPI_CPU0_CPU1_P1P1_DP<15>
J 0
(-5215 3460);
DISPLAY 0.659574 (-5215 3460);
PAINT MONO (-5215 3460);
DISPLAY INVISIBLE (-5215 3460);
FORCEPROP 1 LASTPIN (-5225 3450) BN 15
J 2
(-5213 3458);
DISPLAY 0.617021 (-5213 3458);
PAINT GREEN (-5213 3458);
FORCEPROP 2 LAST CDS_LIB mstr_standard
J 0
(-5275 3450);
PAINT MONO (-5275 3450);
DISPLAY INVISIBLE (-5275 3450);
FORCEPROP 1 LAST BODY_TYPE PLUMBING
J 2
(-5275 3500);
DISPLAY 1.446809 (-5275 3500);
PAINT GREEN (-5275 3500);
DISPLAY INVISIBLE (-5275 3500);
FORCEPROP 1 LAST HDL_TAP TRUE
J 2
(-5600 3325);
DISPLAY 1.446809 (-5600 3325);
PAINT GREEN (-5600 3325);
DISPLAY INVISIBLE (-5600 3325);
FORCEPROP 1 LAST PATH I39
J 2
(-5273 3450);
DISPLAY 0.872340 (-5273 3450);
PAINT GREEN (-5273 3450);
DISPLAY INVISIBLE (-5273 3450);
FORCEADD TAP..1
R 2
(-5275 3500);
FORCEPROP 3 LASTPIN (-5225 3500) SIG_NAME UPI_CPU0_CPU1_P1P1_DP<16>
J 0
(-5215 3510);
DISPLAY 0.659574 (-5215 3510);
PAINT MONO (-5215 3510);
DISPLAY INVISIBLE (-5215 3510);
FORCEPROP 1 LASTPIN (-5225 3500) BN 16
J 2
(-5213 3508);
DISPLAY 0.617021 (-5213 3508);
PAINT GREEN (-5213 3508);
FORCEPROP 2 LAST CDS_LIB mstr_standard
J 0
(-5275 3500);
PAINT MONO (-5275 3500);
DISPLAY INVISIBLE (-5275 3500);
FORCEPROP 1 LAST BODY_TYPE PLUMBING
J 2
(-5275 3550);
DISPLAY 1.446809 (-5275 3550);
PAINT GREEN (-5275 3550);
DISPLAY INVISIBLE (-5275 3550);
FORCEPROP 1 LAST HDL_TAP TRUE
J 2
(-5600 3375);
DISPLAY 1.446809 (-5600 3375);
PAINT GREEN (-5600 3375);
DISPLAY INVISIBLE (-5600 3375);
FORCEPROP 1 LAST PATH I40
J 2
(-5273 3500);
DISPLAY 0.872340 (-5273 3500);
PAINT GREEN (-5273 3500);
DISPLAY INVISIBLE (-5273 3500);
FORCEADD TAP..1
R 2
(-5275 3550);
FORCEPROP 3 LASTPIN (-5225 3550) SIG_NAME UPI_CPU0_CPU1_P1P1_DP<17>
J 0
(-5215 3560);
DISPLAY 0.659574 (-5215 3560);
PAINT MONO (-5215 3560);
DISPLAY INVISIBLE (-5215 3560);
FORCEPROP 1 LASTPIN (-5225 3550) BN 17
J 2
(-5213 3558);
DISPLAY 0.617021 (-5213 3558);
PAINT GREEN (-5213 3558);
FORCEPROP 2 LAST CDS_LIB mstr_standard
J 0
(-5275 3550);
PAINT MONO (-5275 3550);
DISPLAY INVISIBLE (-5275 3550);
FORCEPROP 1 LAST BODY_TYPE PLUMBING
J 2
(-5275 3600);
DISPLAY 1.446809 (-5275 3600);
PAINT GREEN (-5275 3600);
DISPLAY INVISIBLE (-5275 3600);
FORCEPROP 1 LAST HDL_TAP TRUE
J 2
(-5600 3425);
DISPLAY 1.446809 (-5600 3425);
PAINT GREEN (-5600 3425);
DISPLAY INVISIBLE (-5600 3425);
FORCEPROP 1 LAST PATH I41
J 2
(-5273 3550);
DISPLAY 0.872340 (-5273 3550);
PAINT GREEN (-5273 3550);
DISPLAY INVISIBLE (-5273 3550);
FORCEADD TAP..1
R 2
(-5275 2550);
FORCEPROP 3 LASTPIN (-5225 2550) SIG_NAME UPI_CPU0_CPU1_P1P1_DP<18>
J 0
(-5215 2560);
DISPLAY 0.659574 (-5215 2560);
PAINT MONO (-5215 2560);
DISPLAY INVISIBLE (-5215 2560);
FORCEPROP 1 LASTPIN (-5225 2550) BN 18
J 2
(-5213 2558);
DISPLAY 0.617021 (-5213 2558);
PAINT GREEN (-5213 2558);
FORCEPROP 2 LAST CDS_LIB mstr_standard
J 0
(-5275 2550);
PAINT MONO (-5275 2550);
DISPLAY INVISIBLE (-5275 2550);
FORCEPROP 1 LAST BODY_TYPE PLUMBING
J 2
(-5275 2600);
DISPLAY 1.446809 (-5275 2600);
PAINT GREEN (-5275 2600);
DISPLAY INVISIBLE (-5275 2600);
FORCEPROP 1 LAST HDL_TAP TRUE
J 2
(-5600 2425);
DISPLAY 1.446809 (-5600 2425);
PAINT GREEN (-5600 2425);
DISPLAY INVISIBLE (-5600 2425);
FORCEPROP 1 LAST PATH I42
J 2
(-5273 2550);
DISPLAY 0.872340 (-5273 2550);
PAINT GREEN (-5273 2550);
DISPLAY INVISIBLE (-5273 2550);
FORCEADD TAP..1
R 2
(-5275 2600);
FORCEPROP 3 LASTPIN (-5225 2600) SIG_NAME UPI_CPU0_CPU1_P1P1_DP<19>
J 0
(-5215 2610);
DISPLAY 0.659574 (-5215 2610);
PAINT MONO (-5215 2610);
DISPLAY INVISIBLE (-5215 2610);
FORCEPROP 1 LASTPIN (-5225 2600) BN 19
J 2
(-5213 2608);
DISPLAY 0.617021 (-5213 2608);
PAINT GREEN (-5213 2608);
FORCEPROP 2 LAST CDS_LIB mstr_standard
J 0
(-5275 2600);
PAINT MONO (-5275 2600);
DISPLAY INVISIBLE (-5275 2600);
FORCEPROP 1 LAST BODY_TYPE PLUMBING
J 2
(-5275 2650);
DISPLAY 1.446809 (-5275 2650);
PAINT GREEN (-5275 2650);
DISPLAY INVISIBLE (-5275 2650);
FORCEPROP 1 LAST HDL_TAP TRUE
J 2
(-5600 2475);
DISPLAY 1.446809 (-5600 2475);
PAINT GREEN (-5600 2475);
DISPLAY INVISIBLE (-5600 2475);
FORCEPROP 1 LAST PATH I43
J 2
(-5273 2600);
DISPLAY 0.872340 (-5273 2600);
PAINT GREEN (-5273 2600);
DISPLAY INVISIBLE (-5273 2600);
FORCEADD TAP..1
(-2625 1800);
FORCEPROP 3 LASTPIN (-2675 1800) SIG_NAME UPI_CPU1_CPU0_P1P1_DN<3>
J 0
(-2665 1810);
DISPLAY 0.659574 (-2665 1810);
PAINT MONO (-2665 1810);
DISPLAY INVISIBLE (-2665 1810);
FORCEPROP 1 LASTPIN (-2675 1800) BN 3
J 0
(-2687 1808);
DISPLAY 0.617021 (-2687 1808);
PAINT GREEN (-2687 1808);
FORCEPROP 2 LAST CDS_LIB mstr_standard
J 0
(-2625 1800);
PAINT MONO (-2625 1800);
DISPLAY INVISIBLE (-2625 1800);
FORCEPROP 1 LAST BODY_TYPE PLUMBING
J 0
(-2625 1850);
DISPLAY 1.446809 (-2625 1850);
PAINT GREEN (-2625 1850);
DISPLAY INVISIBLE (-2625 1850);
FORCEPROP 1 LAST HDL_TAP TRUE
J 0
(-2300 1675);
DISPLAY 1.446809 (-2300 1675);
PAINT GREEN (-2300 1675);
DISPLAY INVISIBLE (-2300 1675);
FORCEPROP 1 LAST PATH I46
J 0
(-2627 1800);
DISPLAY 0.872340 (-2627 1800);
PAINT GREEN (-2627 1800);
DISPLAY INVISIBLE (-2627 1800);
FORCEADD TAP..1
(-2625 1750);
FORCEPROP 3 LASTPIN (-2675 1750) SIG_NAME UPI_CPU1_CPU0_P1P1_DN<2>
J 0
(-2665 1760);
DISPLAY 0.659574 (-2665 1760);
PAINT MONO (-2665 1760);
DISPLAY INVISIBLE (-2665 1760);
FORCEPROP 1 LASTPIN (-2675 1750) BN 2
J 0
(-2687 1758);
DISPLAY 0.617021 (-2687 1758);
PAINT GREEN (-2687 1758);
FORCEPROP 2 LAST CDS_LIB mstr_standard
J 0
(-2625 1750);
PAINT MONO (-2625 1750);
DISPLAY INVISIBLE (-2625 1750);
FORCEPROP 1 LAST BODY_TYPE PLUMBING
J 0
(-2625 1800);
DISPLAY 1.446809 (-2625 1800);
PAINT GREEN (-2625 1800);
DISPLAY INVISIBLE (-2625 1800);
FORCEPROP 1 LAST HDL_TAP TRUE
J 0
(-2300 1625);
DISPLAY 1.446809 (-2300 1625);
PAINT GREEN (-2300 1625);
DISPLAY INVISIBLE (-2300 1625);
FORCEPROP 1 LAST PATH I47
J 0
(-2627 1750);
DISPLAY 0.872340 (-2627 1750);
PAINT GREEN (-2627 1750);
DISPLAY INVISIBLE (-2627 1750);
FORCEADD TAP..1
(-2625 1850);
FORCEPROP 3 LASTPIN (-2675 1850) SIG_NAME UPI_CPU1_CPU0_P1P1_DN<4>
J 0
(-2665 1860);
DISPLAY 0.659574 (-2665 1860);
PAINT MONO (-2665 1860);
DISPLAY INVISIBLE (-2665 1860);
FORCEPROP 1 LASTPIN (-2675 1850) BN 4
J 0
(-2687 1858);
DISPLAY 0.617021 (-2687 1858);
PAINT GREEN (-2687 1858);
FORCEPROP 2 LAST CDS_LIB mstr_standard
J 0
(-2625 1850);
PAINT MONO (-2625 1850);
DISPLAY INVISIBLE (-2625 1850);
FORCEPROP 1 LAST BODY_TYPE PLUMBING
J 0
(-2625 1900);
DISPLAY 1.446809 (-2625 1900);
PAINT GREEN (-2625 1900);
DISPLAY INVISIBLE (-2625 1900);
FORCEPROP 1 LAST HDL_TAP TRUE
J 0
(-2300 1725);
DISPLAY 1.446809 (-2300 1725);
PAINT GREEN (-2300 1725);
DISPLAY INVISIBLE (-2300 1725);
FORCEPROP 1 LAST PATH I48
J 0
(-2627 1850);
DISPLAY 0.872340 (-2627 1850);
PAINT GREEN (-2627 1850);
DISPLAY INVISIBLE (-2627 1850);
FORCEADD TAP..1
R 2
(-5725 1800);
FORCEPROP 3 LASTPIN (-5675 1800) SIG_NAME UPI_CPU0_CPU1_P1P1_DN<3>
J 0
(-5665 1810);
DISPLAY 0.659574 (-5665 1810);
PAINT MONO (-5665 1810);
DISPLAY INVISIBLE (-5665 1810);
FORCEPROP 1 LASTPIN (-5675 1800) BN 3
J 2
(-5663 1808);
DISPLAY 0.617021 (-5663 1808);
PAINT GREEN (-5663 1808);
FORCEPROP 2 LAST CDS_LIB mstr_standard
J 0
(-5725 1800);
PAINT MONO (-5725 1800);
DISPLAY INVISIBLE (-5725 1800);
FORCEPROP 1 LAST BODY_TYPE PLUMBING
J 2
(-5725 1850);
DISPLAY 1.446809 (-5725 1850);
PAINT GREEN (-5725 1850);
DISPLAY INVISIBLE (-5725 1850);
FORCEPROP 1 LAST HDL_TAP TRUE
J 2
(-6050 1675);
DISPLAY 1.446809 (-6050 1675);
PAINT GREEN (-6050 1675);
DISPLAY INVISIBLE (-6050 1675);
FORCEPROP 1 LAST PATH I5
J 2
(-5723 1800);
DISPLAY 0.872340 (-5723 1800);
PAINT GREEN (-5723 1800);
DISPLAY INVISIBLE (-5723 1800);
FORCEADD TAP..1
(-2625 2150);
FORCEPROP 3 LASTPIN (-2675 2150) SIG_NAME UPI_CPU1_CPU0_P1P1_DN<10>
J 0
(-2665 2160);
DISPLAY 0.659574 (-2665 2160);
PAINT MONO (-2665 2160);
DISPLAY INVISIBLE (-2665 2160);
FORCEPROP 1 LASTPIN (-2675 2150) BN 10
J 0
(-2687 2158);
DISPLAY 0.617021 (-2687 2158);
PAINT GREEN (-2687 2158);
FORCEPROP 2 LAST CDS_LIB mstr_standard
J 0
(-2625 2150);
PAINT MONO (-2625 2150);
DISPLAY INVISIBLE (-2625 2150);
FORCEPROP 1 LAST BODY_TYPE PLUMBING
J 0
(-2625 2200);
DISPLAY 1.446809 (-2625 2200);
PAINT GREEN (-2625 2200);
DISPLAY INVISIBLE (-2625 2200);
FORCEPROP 1 LAST HDL_TAP TRUE
J 0
(-2300 2025);
DISPLAY 1.446809 (-2300 2025);
PAINT GREEN (-2300 2025);
DISPLAY INVISIBLE (-2300 2025);
FORCEPROP 1 LAST PATH I54
J 0
(-2627 2150);
DISPLAY 0.872340 (-2627 2150);
PAINT GREEN (-2627 2150);
DISPLAY INVISIBLE (-2627 2150);
FORCEADD TAP..1
(-2625 2250);
FORCEPROP 3 LASTPIN (-2675 2250) SIG_NAME UPI_CPU1_CPU0_P1P1_DN<12>
J 0
(-2665 2260);
DISPLAY 0.659574 (-2665 2260);
PAINT MONO (-2665 2260);
DISPLAY INVISIBLE (-2665 2260);
FORCEPROP 1 LASTPIN (-2675 2250) BN 12
J 0
(-2687 2258);
DISPLAY 0.617021 (-2687 2258);
PAINT GREEN (-2687 2258);
FORCEPROP 2 LAST CDS_LIB mstr_standard
J 0
(-2625 2250);
PAINT MONO (-2625 2250);
DISPLAY INVISIBLE (-2625 2250);
FORCEPROP 1 LAST BODY_TYPE PLUMBING
J 0
(-2625 2300);
DISPLAY 1.446809 (-2625 2300);
PAINT GREEN (-2625 2300);
DISPLAY INVISIBLE (-2625 2300);
FORCEPROP 1 LAST HDL_TAP TRUE
J 0
(-2300 2125);
DISPLAY 1.446809 (-2300 2125);
PAINT GREEN (-2300 2125);
DISPLAY INVISIBLE (-2300 2125);
FORCEPROP 1 LAST PATH I56
J 0
(-2627 2250);
DISPLAY 0.872340 (-2627 2250);
PAINT GREEN (-2627 2250);
DISPLAY INVISIBLE (-2627 2250);
FORCEADD TAP..1
R 2
(-5725 1750);
FORCEPROP 3 LASTPIN (-5675 1750) SIG_NAME UPI_CPU0_CPU1_P1P1_DN<2>
J 0
(-5665 1760);
DISPLAY 0.659574 (-5665 1760);
PAINT MONO (-5665 1760);
DISPLAY INVISIBLE (-5665 1760);
FORCEPROP 1 LASTPIN (-5675 1750) BN 2
J 2
(-5663 1758);
DISPLAY 0.617021 (-5663 1758);
PAINT GREEN (-5663 1758);
FORCEPROP 2 LAST CDS_LIB mstr_standard
J 0
(-5725 1750);
PAINT MONO (-5725 1750);
DISPLAY INVISIBLE (-5725 1750);
FORCEPROP 1 LAST BODY_TYPE PLUMBING
J 2
(-5725 1800);
DISPLAY 1.446809 (-5725 1800);
PAINT GREEN (-5725 1800);
DISPLAY INVISIBLE (-5725 1800);
FORCEPROP 1 LAST HDL_TAP TRUE
J 2
(-6050 1625);
DISPLAY 1.446809 (-6050 1625);
PAINT GREEN (-6050 1625);
DISPLAY INVISIBLE (-6050 1625);
FORCEPROP 1 LAST PATH I6
J 2
(-5723 1750);
DISPLAY 0.872340 (-5723 1750);
PAINT GREEN (-5723 1750);
DISPLAY INVISIBLE (-5723 1750);
FORCEADD TAP..1
(-2625 2500);
FORCEPROP 3 LASTPIN (-2675 2500) SIG_NAME UPI_CPU1_CPU0_P1P1_DN<17>
J 0
(-2665 2510);
DISPLAY 0.659574 (-2665 2510);
PAINT MONO (-2665 2510);
DISPLAY INVISIBLE (-2665 2510);
FORCEPROP 1 LASTPIN (-2675 2500) BN 17
J 0
(-2687 2508);
DISPLAY 0.617021 (-2687 2508);
PAINT GREEN (-2687 2508);
FORCEPROP 2 LAST CDS_LIB mstr_standard
J 0
(-2625 2500);
PAINT MONO (-2625 2500);
DISPLAY INVISIBLE (-2625 2500);
FORCEPROP 1 LAST BODY_TYPE PLUMBING
J 0
(-2625 2550);
DISPLAY 1.446809 (-2625 2550);
PAINT GREEN (-2625 2550);
DISPLAY INVISIBLE (-2625 2550);
FORCEPROP 1 LAST HDL_TAP TRUE
J 0
(-2300 2375);
DISPLAY 1.446809 (-2300 2375);
PAINT GREEN (-2300 2375);
DISPLAY INVISIBLE (-2300 2375);
FORCEPROP 1 LAST PATH I60
J 0
(-2627 2500);
DISPLAY 0.872340 (-2627 2500);
PAINT GREEN (-2627 2500);
DISPLAY INVISIBLE (-2627 2500);
FORCEADD TAP..1
(-2625 2450);
FORCEPROP 3 LASTPIN (-2675 2450) SIG_NAME UPI_CPU1_CPU0_P1P1_DN<16>
J 0
(-2665 2460);
DISPLAY 0.659574 (-2665 2460);
PAINT MONO (-2665 2460);
DISPLAY INVISIBLE (-2665 2460);
FORCEPROP 1 LASTPIN (-2675 2450) BN 16
J 0
(-2687 2458);
DISPLAY 0.617021 (-2687 2458);
PAINT GREEN (-2687 2458);
FORCEPROP 2 LAST CDS_LIB mstr_standard
J 0
(-2625 2450);
PAINT MONO (-2625 2450);
DISPLAY INVISIBLE (-2625 2450);
FORCEPROP 1 LAST BODY_TYPE PLUMBING
J 0
(-2625 2500);
DISPLAY 1.446809 (-2625 2500);
PAINT GREEN (-2625 2500);
DISPLAY INVISIBLE (-2625 2500);
FORCEPROP 1 LAST HDL_TAP TRUE
J 0
(-2300 2325);
DISPLAY 1.446809 (-2300 2325);
PAINT GREEN (-2300 2325);
DISPLAY INVISIBLE (-2300 2325);
FORCEPROP 1 LAST PATH I61
J 0
(-2627 2450);
DISPLAY 0.872340 (-2627 2450);
PAINT GREEN (-2627 2450);
DISPLAY INVISIBLE (-2627 2450);
FORCEADD TAP..1
(-2950 2800);
FORCEPROP 3 LASTPIN (-3000 2800) SIG_NAME UPI_CPU1_CPU0_P1P1_DP<2>
J 0
(-2990 2810);
DISPLAY 0.659574 (-2990 2810);
PAINT MONO (-2990 2810);
DISPLAY INVISIBLE (-2990 2810);
FORCEPROP 1 LASTPIN (-3000 2800) BN 2
J 0
(-3012 2808);
DISPLAY 0.617021 (-3012 2808);
PAINT GREEN (-3012 2808);
FORCEPROP 2 LAST CDS_LIB mstr_standard
J 0
(-2950 2800);
PAINT MONO (-2950 2800);
DISPLAY INVISIBLE (-2950 2800);
FORCEPROP 1 LAST BODY_TYPE PLUMBING
J 0
(-2950 2850);
DISPLAY 1.446809 (-2950 2850);
PAINT GREEN (-2950 2850);
DISPLAY INVISIBLE (-2950 2850);
FORCEPROP 1 LAST HDL_TAP TRUE
J 0
(-2625 2675);
DISPLAY 1.446809 (-2625 2675);
PAINT GREEN (-2625 2675);
DISPLAY INVISIBLE (-2625 2675);
FORCEPROP 1 LAST PATH I66
J 0
(-2952 2800);
DISPLAY 0.872340 (-2952 2800);
PAINT GREEN (-2952 2800);
DISPLAY INVISIBLE (-2952 2800);
FORCEADD TAP..1
(-2950 2850);
FORCEPROP 3 LASTPIN (-3000 2850) SIG_NAME UPI_CPU1_CPU0_P1P1_DP<3>
J 0
(-2990 2860);
DISPLAY 0.659574 (-2990 2860);
PAINT MONO (-2990 2860);
DISPLAY INVISIBLE (-2990 2860);
FORCEPROP 1 LASTPIN (-3000 2850) BN 3
J 0
(-3012 2858);
DISPLAY 0.617021 (-3012 2858);
PAINT GREEN (-3012 2858);
FORCEPROP 2 LAST CDS_LIB mstr_standard
J 0
(-2950 2850);
PAINT MONO (-2950 2850);
DISPLAY INVISIBLE (-2950 2850);
FORCEPROP 1 LAST BODY_TYPE PLUMBING
J 0
(-2950 2900);
DISPLAY 1.446809 (-2950 2900);
PAINT GREEN (-2950 2900);
DISPLAY INVISIBLE (-2950 2900);
FORCEPROP 1 LAST HDL_TAP TRUE
J 0
(-2625 2725);
DISPLAY 1.446809 (-2625 2725);
PAINT GREEN (-2625 2725);
DISPLAY INVISIBLE (-2625 2725);
FORCEPROP 1 LAST PATH I67
J 0
(-2952 2850);
DISPLAY 0.872340 (-2952 2850);
PAINT GREEN (-2952 2850);
DISPLAY INVISIBLE (-2952 2850);
FORCEADD TAP..1
(-2950 2900);
FORCEPROP 3 LASTPIN (-3000 2900) SIG_NAME UPI_CPU1_CPU0_P1P1_DP<4>
J 0
(-2990 2910);
DISPLAY 0.659574 (-2990 2910);
PAINT MONO (-2990 2910);
DISPLAY INVISIBLE (-2990 2910);
FORCEPROP 1 LASTPIN (-3000 2900) BN 4
J 0
(-3012 2908);
DISPLAY 0.617021 (-3012 2908);
PAINT GREEN (-3012 2908);
FORCEPROP 2 LAST CDS_LIB mstr_standard
J 0
(-2950 2900);
PAINT MONO (-2950 2900);
DISPLAY INVISIBLE (-2950 2900);
FORCEPROP 1 LAST BODY_TYPE PLUMBING
J 0
(-2950 2950);
DISPLAY 1.446809 (-2950 2950);
PAINT GREEN (-2950 2950);
DISPLAY INVISIBLE (-2950 2950);
FORCEPROP 1 LAST HDL_TAP TRUE
J 0
(-2625 2775);
DISPLAY 1.446809 (-2625 2775);
PAINT GREEN (-2625 2775);
DISPLAY INVISIBLE (-2625 2775);
FORCEPROP 1 LAST PATH I69
J 0
(-2952 2900);
DISPLAY 0.872340 (-2952 2900);
PAINT GREEN (-2952 2900);
DISPLAY INVISIBLE (-2952 2900);
FORCEADD TAP..1
(-2950 3200);
FORCEPROP 3 LASTPIN (-3000 3200) SIG_NAME UPI_CPU1_CPU0_P1P1_DP<10>
J 0
(-2990 3210);
DISPLAY 0.659574 (-2990 3210);
PAINT MONO (-2990 3210);
DISPLAY INVISIBLE (-2990 3210);
FORCEPROP 1 LASTPIN (-3000 3200) BN 10
J 0
(-3012 3208);
DISPLAY 0.617021 (-3012 3208);
PAINT GREEN (-3012 3208);
FORCEPROP 2 LAST CDS_LIB mstr_standard
J 0
(-2950 3200);
PAINT MONO (-2950 3200);
DISPLAY INVISIBLE (-2950 3200);
FORCEPROP 1 LAST BODY_TYPE PLUMBING
J 0
(-2950 3250);
DISPLAY 1.446809 (-2950 3250);
PAINT GREEN (-2950 3250);
DISPLAY INVISIBLE (-2950 3250);
FORCEPROP 1 LAST HDL_TAP TRUE
J 0
(-2625 3075);
DISPLAY 1.446809 (-2625 3075);
PAINT GREEN (-2625 3075);
DISPLAY INVISIBLE (-2625 3075);
FORCEPROP 1 LAST PATH I74
J 0
(-2952 3200);
DISPLAY 0.872340 (-2952 3200);
PAINT GREEN (-2952 3200);
DISPLAY INVISIBLE (-2952 3200);
FORCEADD TAP..1
(-2950 3300);
FORCEPROP 3 LASTPIN (-3000 3300) SIG_NAME UPI_CPU1_CPU0_P1P1_DP<12>
J 0
(-2990 3310);
DISPLAY 0.659574 (-2990 3310);
PAINT MONO (-2990 3310);
DISPLAY INVISIBLE (-2990 3310);
FORCEPROP 1 LASTPIN (-3000 3300) BN 12
J 0
(-3012 3308);
DISPLAY 0.617021 (-3012 3308);
PAINT GREEN (-3012 3308);
FORCEPROP 2 LAST CDS_LIB mstr_standard
J 0
(-2950 3300);
PAINT MONO (-2950 3300);
DISPLAY INVISIBLE (-2950 3300);
FORCEPROP 1 LAST BODY_TYPE PLUMBING
J 0
(-2950 3350);
DISPLAY 1.446809 (-2950 3350);
PAINT GREEN (-2950 3350);
DISPLAY INVISIBLE (-2950 3350);
FORCEPROP 1 LAST HDL_TAP TRUE
J 0
(-2625 3175);
DISPLAY 1.446809 (-2625 3175);
PAINT GREEN (-2625 3175);
DISPLAY INVISIBLE (-2625 3175);
FORCEPROP 1 LAST PATH I76
J 0
(-2952 3300);
DISPLAY 0.872340 (-2952 3300);
PAINT GREEN (-2952 3300);
DISPLAY INVISIBLE (-2952 3300);
FORCEADD TAP..1
(-2950 3500);
FORCEPROP 3 LASTPIN (-3000 3500) SIG_NAME UPI_CPU1_CPU0_P1P1_DP<16>
J 0
(-2990 3510);
DISPLAY 0.659574 (-2990 3510);
PAINT MONO (-2990 3510);
DISPLAY INVISIBLE (-2990 3510);
FORCEPROP 1 LASTPIN (-3000 3500) BN 16
J 0
(-3012 3508);
DISPLAY 0.617021 (-3012 3508);
PAINT GREEN (-3012 3508);
FORCEPROP 2 LAST CDS_LIB mstr_standard
J 0
(-2950 3500);
PAINT MONO (-2950 3500);
DISPLAY INVISIBLE (-2950 3500);
FORCEPROP 1 LAST BODY_TYPE PLUMBING
J 0
(-2950 3550);
DISPLAY 1.446809 (-2950 3550);
PAINT GREEN (-2950 3550);
DISPLAY INVISIBLE (-2950 3550);
FORCEPROP 1 LAST HDL_TAP TRUE
J 0
(-2625 3375);
DISPLAY 1.446809 (-2625 3375);
PAINT GREEN (-2625 3375);
DISPLAY INVISIBLE (-2625 3375);
FORCEPROP 1 LAST PATH I80
J 0
(-2952 3500);
DISPLAY 0.872340 (-2952 3500);
PAINT GREEN (-2952 3500);
DISPLAY INVISIBLE (-2952 3500);
FORCEADD TAP..1
(-2950 3550);
FORCEPROP 3 LASTPIN (-3000 3550) SIG_NAME UPI_CPU1_CPU0_P1P1_DP<17>
J 0
(-2990 3560);
DISPLAY 0.659574 (-2990 3560);
PAINT MONO (-2990 3560);
DISPLAY INVISIBLE (-2990 3560);
FORCEPROP 1 LASTPIN (-3000 3550) BN 17
J 0
(-3012 3558);
DISPLAY 0.617021 (-3012 3558);
PAINT GREEN (-3012 3558);
FORCEPROP 2 LAST CDS_LIB mstr_standard
J 0
(-2950 3550);
PAINT MONO (-2950 3550);
DISPLAY INVISIBLE (-2950 3550);
FORCEPROP 1 LAST BODY_TYPE PLUMBING
J 0
(-2950 3600);
DISPLAY 1.446809 (-2950 3600);
PAINT GREEN (-2950 3600);
DISPLAY INVISIBLE (-2950 3600);
FORCEPROP 1 LAST HDL_TAP TRUE
J 0
(-2625 3425);
DISPLAY 1.446809 (-2625 3425);
PAINT GREEN (-2625 3425);
DISPLAY INVISIBLE (-2625 3425);
FORCEPROP 1 LAST PATH I82
J 0
(-2952 3550);
DISPLAY 0.872340 (-2952 3550);
PAINT GREEN (-2952 3550);
DISPLAY INVISIBLE (-2952 3550);
FORCEADD OFFPAGE..2
(-1750 3750);
FORCEPROP 2 LAST $XR0 34 
J 0
(-1561 3750);
DISPLAY 0.638298 (-1561 3750);
PAINT MONO (-1561 3750);
FORCEPROP 2 LAST CDS_LIB mstr_standard
J 0
(-1750 3750);
PAINT MONO (-1750 3750);
DISPLAY INVISIBLE (-1750 3750);
FORCEPROP 1 LAST OFFPAGE TRUE
J 0
(-1425 3625);
DISPLAY 1.170213 (-1425 3625);
PAINT GREEN (-1425 3625);
DISPLAY INVISIBLE (-1425 3625);
FORCEPROP 1 LAST COMMENT_BODY TRUE
J 0
(-1795 3655);
DISPLAY 1.170213 (-1795 3655);
PAINT GREEN (-1795 3655);
DISPLAY INVISIBLE (-1795 3655);
FORCEPROP 2 LAST PATH I84
J 0
(-1575 3825);
DISPLAY 1.021277 (-1575 3825);
PAINT ORANGE (-1575 3825);
DISPLAY INVISIBLE (-1575 3825);
FORCEADD OFFPAGE..2
(-1750 3800);
FORCEPROP 2 LAST $XR0 34 
J 0
(-1561 3800);
DISPLAY 0.638298 (-1561 3800);
PAINT MONO (-1561 3800);
FORCEPROP 2 LAST CDS_LIB mstr_standard
J 0
(-1750 3800);
PAINT MONO (-1750 3800);
DISPLAY INVISIBLE (-1750 3800);
FORCEPROP 1 LAST OFFPAGE TRUE
J 0
(-1425 3675);
DISPLAY 1.170213 (-1425 3675);
PAINT GREEN (-1425 3675);
DISPLAY INVISIBLE (-1425 3675);
FORCEPROP 1 LAST COMMENT_BODY TRUE
J 0
(-1795 3705);
DISPLAY 1.170213 (-1795 3705);
PAINT GREEN (-1795 3705);
DISPLAY INVISIBLE (-1795 3705);
FORCEPROP 2 LAST PATH I85
J 0
(-1575 3875);
DISPLAY 1.021277 (-1575 3875);
PAINT ORANGE (-1575 3875);
DISPLAY INVISIBLE (-1575 3875);
FORCEADD TAP..1
R 2
(-5725 2700);
FORCEPROP 3 LASTPIN (-5675 2700) SIG_NAME UPI_CPU0_CPU1_P1P1_DN<0>
J 0
(-5665 2710);
DISPLAY 0.659574 (-5665 2710);
PAINT MONO (-5665 2710);
DISPLAY INVISIBLE (-5665 2710);
FORCEPROP 1 LASTPIN (-5675 2700) BN 0
J 2
(-5663 2708);
DISPLAY 0.617021 (-5663 2708);
PAINT GREEN (-5663 2708);
FORCEPROP 2 LAST CDS_LIB mstr_standard
J 0
(-5725 2700);
PAINT MONO (-5725 2700);
DISPLAY INVISIBLE (-5725 2700);
FORCEPROP 1 LAST BODY_TYPE PLUMBING
J 2
(-5725 2750);
DISPLAY 1.446809 (-5725 2750);
PAINT GREEN (-5725 2750);
DISPLAY INVISIBLE (-5725 2750);
FORCEPROP 1 LAST HDL_TAP TRUE
J 2
(-6050 2575);
DISPLAY 1.446809 (-6050 2575);
PAINT GREEN (-6050 2575);
DISPLAY INVISIBLE (-6050 2575);
FORCEPROP 1 LAST PATH I86
J 2
(-5723 2700);
DISPLAY 0.872340 (-5723 2700);
PAINT GREEN (-5723 2700);
DISPLAY INVISIBLE (-5723 2700);
FORCEADD TAP..1
R 2
(-5725 1700);
FORCEPROP 3 LASTPIN (-5675 1700) SIG_NAME UPI_CPU0_CPU1_P1P1_DN<1>
J 0
(-5665 1710);
DISPLAY 0.659574 (-5665 1710);
PAINT MONO (-5665 1710);
DISPLAY INVISIBLE (-5665 1710);
FORCEPROP 1 LASTPIN (-5675 1700) BN 1
J 2
(-5663 1708);
DISPLAY 0.617021 (-5663 1708);
PAINT GREEN (-5663 1708);
FORCEPROP 2 LAST CDS_LIB mstr_standard
J 0
(-5725 1700);
PAINT MONO (-5725 1700);
DISPLAY INVISIBLE (-5725 1700);
FORCEPROP 1 LAST BODY_TYPE PLUMBING
J 2
(-5725 1750);
DISPLAY 1.446809 (-5725 1750);
PAINT GREEN (-5725 1750);
DISPLAY INVISIBLE (-5725 1750);
FORCEPROP 1 LAST HDL_TAP TRUE
J 2
(-6050 1575);
DISPLAY 1.446809 (-6050 1575);
PAINT GREEN (-6050 1575);
DISPLAY INVISIBLE (-6050 1575);
FORCEPROP 1 LAST PATH I87
J 2
(-5723 1700);
DISPLAY 0.872340 (-5723 1700);
PAINT GREEN (-5723 1700);
DISPLAY INVISIBLE (-5723 1700);
FORCEADD TAP..1
R 2
(-5275 1650);
FORCEPROP 3 LASTPIN (-5225 1650) SIG_NAME UPI_CPU0_CPU1_P1P1_DP<0>
J 0
(-5215 1660);
DISPLAY 0.659574 (-5215 1660);
PAINT MONO (-5215 1660);
DISPLAY INVISIBLE (-5215 1660);
FORCEPROP 1 LASTPIN (-5225 1650) BN 0
J 2
(-5213 1658);
DISPLAY 0.617021 (-5213 1658);
PAINT GREEN (-5213 1658);
FORCEPROP 2 LAST CDS_LIB mstr_standard
J 0
(-5275 1650);
PAINT MONO (-5275 1650);
DISPLAY INVISIBLE (-5275 1650);
FORCEPROP 1 LAST BODY_TYPE PLUMBING
J 2
(-5275 1700);
DISPLAY 1.446809 (-5275 1700);
PAINT GREEN (-5275 1700);
DISPLAY INVISIBLE (-5275 1700);
FORCEPROP 1 LAST HDL_TAP TRUE
J 2
(-5600 1525);
DISPLAY 1.446809 (-5600 1525);
PAINT GREEN (-5600 1525);
DISPLAY INVISIBLE (-5600 1525);
FORCEPROP 1 LAST PATH I88
J 2
(-5273 1650);
DISPLAY 0.872340 (-5273 1650);
PAINT GREEN (-5273 1650);
DISPLAY INVISIBLE (-5273 1650);
FORCEADD TAP..1
R 2
(-5275 2750);
FORCEPROP 3 LASTPIN (-5225 2750) SIG_NAME UPI_CPU0_CPU1_P1P1_DP<1>
J 0
(-5215 2760);
DISPLAY 0.659574 (-5215 2760);
PAINT MONO (-5215 2760);
DISPLAY INVISIBLE (-5215 2760);
FORCEPROP 1 LASTPIN (-5225 2750) BN 1
J 2
(-5213 2758);
DISPLAY 0.617021 (-5213 2758);
PAINT GREEN (-5213 2758);
FORCEPROP 2 LAST CDS_LIB mstr_standard
J 0
(-5275 2750);
PAINT MONO (-5275 2750);
DISPLAY INVISIBLE (-5275 2750);
FORCEPROP 1 LAST BODY_TYPE PLUMBING
J 2
(-5275 2800);
DISPLAY 1.446809 (-5275 2800);
PAINT GREEN (-5275 2800);
DISPLAY INVISIBLE (-5275 2800);
FORCEPROP 1 LAST HDL_TAP TRUE
J 2
(-5600 2625);
DISPLAY 1.446809 (-5600 2625);
PAINT GREEN (-5600 2625);
DISPLAY INVISIBLE (-5600 2625);
FORCEPROP 1 LAST PATH I89
J 2
(-5273 2750);
DISPLAY 0.872340 (-5273 2750);
PAINT GREEN (-5273 2750);
DISPLAY INVISIBLE (-5273 2750);
FORCEADD TAP..1
R 2
(-5725 1850);
FORCEPROP 3 LASTPIN (-5675 1850) SIG_NAME UPI_CPU0_CPU1_P1P1_DN<4>
J 0
(-5665 1860);
DISPLAY 0.659574 (-5665 1860);
PAINT MONO (-5665 1860);
DISPLAY INVISIBLE (-5665 1860);
FORCEPROP 1 LASTPIN (-5675 1850) BN 4
J 2
(-5663 1858);
DISPLAY 0.617021 (-5663 1858);
PAINT GREEN (-5663 1858);
FORCEPROP 2 LAST CDS_LIB mstr_standard
J 0
(-5725 1850);
PAINT MONO (-5725 1850);
DISPLAY INVISIBLE (-5725 1850);
FORCEPROP 1 LAST BODY_TYPE PLUMBING
J 2
(-5725 1900);
DISPLAY 1.446809 (-5725 1900);
PAINT GREEN (-5725 1900);
DISPLAY INVISIBLE (-5725 1900);
FORCEPROP 1 LAST HDL_TAP TRUE
J 2
(-6050 1725);
DISPLAY 1.446809 (-6050 1725);
PAINT GREEN (-6050 1725);
DISPLAY INVISIBLE (-6050 1725);
FORCEPROP 1 LAST PATH I90
J 2
(-5723 1850);
DISPLAY 0.872340 (-5723 1850);
PAINT GREEN (-5723 1850);
DISPLAY INVISIBLE (-5723 1850);
FORCEADD TAP..1
R 2
(-5725 1950);
FORCEPROP 3 LASTPIN (-5675 1950) SIG_NAME UPI_CPU0_CPU1_P1P1_DN<6>
J 0
(-5665 1960);
DISPLAY 0.659574 (-5665 1960);
PAINT MONO (-5665 1960);
DISPLAY INVISIBLE (-5665 1960);
FORCEPROP 1 LASTPIN (-5675 1950) BN 6
J 2
(-5663 1958);
DISPLAY 0.617021 (-5663 1958);
PAINT GREEN (-5663 1958);
FORCEPROP 2 LAST CDS_LIB mstr_standard
J 0
(-5725 1950);
PAINT MONO (-5725 1950);
DISPLAY INVISIBLE (-5725 1950);
FORCEPROP 1 LAST BODY_TYPE PLUMBING
J 2
(-5725 2000);
DISPLAY 1.446809 (-5725 2000);
PAINT GREEN (-5725 2000);
DISPLAY INVISIBLE (-5725 2000);
FORCEPROP 1 LAST HDL_TAP TRUE
J 2
(-6050 1825);
DISPLAY 1.446809 (-6050 1825);
PAINT GREEN (-6050 1825);
DISPLAY INVISIBLE (-6050 1825);
FORCEPROP 1 LAST PATH I91
J 2
(-5723 1950);
DISPLAY 0.872340 (-5723 1950);
PAINT GREEN (-5723 1950);
DISPLAY INVISIBLE (-5723 1950);
FORCEADD TAP..1
R 2
(-5725 3100);
FORCEPROP 3 LASTPIN (-5675 3100) SIG_NAME UPI_CPU0_CPU1_P1P1_DN<8>
J 0
(-5665 3110);
DISPLAY 0.659574 (-5665 3110);
PAINT MONO (-5665 3110);
DISPLAY INVISIBLE (-5665 3110);
FORCEPROP 1 LASTPIN (-5675 3100) BN 8
J 2
(-5663 3108);
DISPLAY 0.617021 (-5663 3108);
PAINT GREEN (-5663 3108);
FORCEPROP 2 LAST CDS_LIB mstr_standard
J 0
(-5725 3100);
PAINT MONO (-5725 3100);
DISPLAY INVISIBLE (-5725 3100);
FORCEPROP 1 LAST BODY_TYPE PLUMBING
J 2
(-5725 3150);
DISPLAY 1.446809 (-5725 3150);
PAINT GREEN (-5725 3150);
DISPLAY INVISIBLE (-5725 3150);
FORCEPROP 1 LAST HDL_TAP TRUE
J 2
(-6050 2975);
DISPLAY 1.446809 (-6050 2975);
PAINT GREEN (-6050 2975);
DISPLAY INVISIBLE (-6050 2975);
FORCEPROP 1 LAST PATH I92
J 2
(-5723 3100);
DISPLAY 0.872340 (-5723 3100);
PAINT GREEN (-5723 3100);
DISPLAY INVISIBLE (-5723 3100);
FORCEADD TAP..1
R 2
(-5725 3250);
FORCEPROP 3 LASTPIN (-5675 3250) SIG_NAME UPI_CPU0_CPU1_P1P1_DN<11>
J 0
(-5665 3260);
DISPLAY 0.659574 (-5665 3260);
PAINT MONO (-5665 3260);
DISPLAY INVISIBLE (-5665 3260);
FORCEPROP 1 LASTPIN (-5675 3250) BN 11
J 2
(-5663 3258);
DISPLAY 0.617021 (-5663 3258);
PAINT GREEN (-5663 3258);
FORCEPROP 2 LAST CDS_LIB mstr_standard
J 0
(-5725 3250);
PAINT MONO (-5725 3250);
DISPLAY INVISIBLE (-5725 3250);
FORCEPROP 1 LAST BODY_TYPE PLUMBING
J 2
(-5725 3300);
DISPLAY 1.446809 (-5725 3300);
PAINT GREEN (-5725 3300);
DISPLAY INVISIBLE (-5725 3300);
FORCEPROP 1 LAST HDL_TAP TRUE
J 2
(-6050 3125);
DISPLAY 1.446809 (-6050 3125);
PAINT GREEN (-6050 3125);
DISPLAY INVISIBLE (-6050 3125);
FORCEPROP 1 LAST PATH I93
J 2
(-5723 3250);
DISPLAY 0.872340 (-5723 3250);
PAINT GREEN (-5723 3250);
DISPLAY INVISIBLE (-5723 3250);
FORCEADD TAP..1
R 2
(-5725 3300);
FORCEPROP 3 LASTPIN (-5675 3300) SIG_NAME UPI_CPU0_CPU1_P1P1_DN<12>
J 0
(-5665 3310);
DISPLAY 0.659574 (-5665 3310);
PAINT MONO (-5665 3310);
DISPLAY INVISIBLE (-5665 3310);
FORCEPROP 1 LASTPIN (-5675 3300) BN 12
J 2
(-5663 3308);
DISPLAY 0.617021 (-5663 3308);
PAINT GREEN (-5663 3308);
FORCEPROP 2 LAST CDS_LIB mstr_standard
J 0
(-5725 3300);
PAINT MONO (-5725 3300);
DISPLAY INVISIBLE (-5725 3300);
FORCEPROP 1 LAST BODY_TYPE PLUMBING
J 2
(-5725 3350);
DISPLAY 1.446809 (-5725 3350);
PAINT GREEN (-5725 3350);
DISPLAY INVISIBLE (-5725 3350);
FORCEPROP 1 LAST HDL_TAP TRUE
J 2
(-6050 3175);
DISPLAY 1.446809 (-6050 3175);
PAINT GREEN (-6050 3175);
DISPLAY INVISIBLE (-6050 3175);
FORCEPROP 1 LAST PATH I94
J 2
(-5723 3300);
DISPLAY 0.872340 (-5723 3300);
PAINT GREEN (-5723 3300);
DISPLAY INVISIBLE (-5723 3300);
FORCEADD TAP..1
R 2
(-5725 3350);
FORCEPROP 3 LASTPIN (-5675 3350) SIG_NAME UPI_CPU0_CPU1_P1P1_DN<13>
J 0
(-5665 3360);
DISPLAY 0.659574 (-5665 3360);
PAINT MONO (-5665 3360);
DISPLAY INVISIBLE (-5665 3360);
FORCEPROP 1 LASTPIN (-5675 3350) BN 13
J 2
(-5663 3358);
DISPLAY 0.617021 (-5663 3358);
PAINT GREEN (-5663 3358);
FORCEPROP 2 LAST CDS_LIB mstr_standard
J 0
(-5725 3350);
PAINT MONO (-5725 3350);
DISPLAY INVISIBLE (-5725 3350);
FORCEPROP 1 LAST BODY_TYPE PLUMBING
J 2
(-5725 3400);
DISPLAY 1.446809 (-5725 3400);
PAINT GREEN (-5725 3400);
DISPLAY INVISIBLE (-5725 3400);
FORCEPROP 1 LAST HDL_TAP TRUE
J 2
(-6050 3225);
DISPLAY 1.446809 (-6050 3225);
PAINT GREEN (-6050 3225);
DISPLAY INVISIBLE (-6050 3225);
FORCEPROP 1 LAST PATH I95
J 2
(-5723 3350);
DISPLAY 0.872340 (-5723 3350);
PAINT GREEN (-5723 3350);
DISPLAY INVISIBLE (-5723 3350);
FORCEADD TAP..1
R 2
(-5725 2400);
FORCEPROP 3 LASTPIN (-5675 2400) SIG_NAME UPI_CPU0_CPU1_P1P1_DN<15>
J 0
(-5665 2410);
DISPLAY 0.659574 (-5665 2410);
PAINT MONO (-5665 2410);
DISPLAY INVISIBLE (-5665 2410);
FORCEPROP 1 LASTPIN (-5675 2400) BN 15
J 2
(-5663 2408);
DISPLAY 0.617021 (-5663 2408);
PAINT GREEN (-5663 2408);
FORCEPROP 2 LAST CDS_LIB mstr_standard
J 0
(-5725 2400);
PAINT MONO (-5725 2400);
DISPLAY INVISIBLE (-5725 2400);
FORCEPROP 1 LAST BODY_TYPE PLUMBING
J 2
(-5725 2450);
DISPLAY 1.446809 (-5725 2450);
PAINT GREEN (-5725 2450);
DISPLAY INVISIBLE (-5725 2450);
FORCEPROP 1 LAST HDL_TAP TRUE
J 2
(-6050 2275);
DISPLAY 1.446809 (-6050 2275);
PAINT GREEN (-6050 2275);
DISPLAY INVISIBLE (-6050 2275);
FORCEPROP 1 LAST PATH I96
J 2
(-5723 2400);
DISPLAY 0.872340 (-5723 2400);
PAINT GREEN (-5723 2400);
DISPLAY INVISIBLE (-5723 2400);
FORCEADD TAP..1
R 2
(-5725 2450);
FORCEPROP 3 LASTPIN (-5675 2450) SIG_NAME UPI_CPU0_CPU1_P1P1_DN<16>
J 0
(-5665 2460);
DISPLAY 0.659574 (-5665 2460);
PAINT MONO (-5665 2460);
DISPLAY INVISIBLE (-5665 2460);
FORCEPROP 1 LASTPIN (-5675 2450) BN 16
J 2
(-5663 2458);
DISPLAY 0.617021 (-5663 2458);
PAINT GREEN (-5663 2458);
FORCEPROP 2 LAST CDS_LIB mstr_standard
J 0
(-5725 2450);
PAINT MONO (-5725 2450);
DISPLAY INVISIBLE (-5725 2450);
FORCEPROP 1 LAST BODY_TYPE PLUMBING
J 2
(-5725 2500);
DISPLAY 1.446809 (-5725 2500);
PAINT GREEN (-5725 2500);
DISPLAY INVISIBLE (-5725 2500);
FORCEPROP 1 LAST HDL_TAP TRUE
J 2
(-6050 2325);
DISPLAY 1.446809 (-6050 2325);
PAINT GREEN (-6050 2325);
DISPLAY INVISIBLE (-6050 2325);
FORCEPROP 1 LAST PATH I97
J 2
(-5723 2450);
DISPLAY 0.872340 (-5723 2450);
PAINT GREEN (-5723 2450);
DISPLAY INVISIBLE (-5723 2450);
FORCEADD TAP..1
R 2
(-5725 3650);
FORCEPROP 3 LASTPIN (-5675 3650) SIG_NAME UPI_CPU0_CPU1_P1P1_DN<19>
J 0
(-5665 3660);
DISPLAY 0.659574 (-5665 3660);
PAINT MONO (-5665 3660);
DISPLAY INVISIBLE (-5665 3660);
FORCEPROP 1 LASTPIN (-5675 3650) BN 19
J 2
(-5663 3658);
DISPLAY 0.617021 (-5663 3658);
PAINT GREEN (-5663 3658);
FORCEPROP 2 LAST CDS_LIB mstr_standard
J 0
(-5725 3650);
PAINT ORANGE (-5725 3650);
DISPLAY INVISIBLE (-5725 3650);
FORCEPROP 1 LAST BODY_TYPE PLUMBING
J 2
(-5725 3700);
DISPLAY 1.446809 (-5725 3700);
PAINT GREEN (-5725 3700);
DISPLAY INVISIBLE (-5725 3700);
FORCEPROP 1 LAST HDL_TAP TRUE
J 2
(-6050 3525);
DISPLAY 1.446809 (-6050 3525);
PAINT GREEN (-6050 3525);
DISPLAY INVISIBLE (-6050 3525);
FORCEPROP 1 LAST PATH I98
J 2
(-5723 3650);
DISPLAY 0.872340 (-5723 3650);
PAINT GREEN (-5723 3650);
DISPLAY INVISIBLE (-5723 3650);
FORCEADD TAP..1
(-2950 1650);
FORCEPROP 3 LASTPIN (-3000 1650) SIG_NAME UPI_CPU1_CPU0_P1P1_DP<0>
J 0
(-2990 1660);
DISPLAY 0.659574 (-2990 1660);
PAINT MONO (-2990 1660);
DISPLAY INVISIBLE (-2990 1660);
FORCEPROP 1 LASTPIN (-3000 1650) BN 0
J 0
(-3012 1658);
DISPLAY 0.617021 (-3012 1658);
PAINT GREEN (-3012 1658);
FORCEPROP 2 LAST CDS_LIB mstr_standard
J 0
(-2950 1650);
PAINT MONO (-2950 1650);
DISPLAY INVISIBLE (-2950 1650);
FORCEPROP 1 LAST BODY_TYPE PLUMBING
J 0
(-2950 1700);
DISPLAY 1.446809 (-2950 1700);
PAINT GREEN (-2950 1700);
DISPLAY INVISIBLE (-2950 1700);
FORCEPROP 1 LAST HDL_TAP TRUE
J 0
(-2625 1525);
DISPLAY 1.446809 (-2625 1525);
PAINT GREEN (-2625 1525);
DISPLAY INVISIBLE (-2625 1525);
FORCEPROP 1 LAST PATH I99
J 0
(-2952 1650);
DISPLAY 0.872340 (-2952 1650);
PAINT GREEN (-2952 1650);
DISPLAY INVISIBLE (-2952 1650);
FORCEADD DESIGN_NOTE..1
(-4675 1350);
FORCEPROP 0 LAST L1 CPU SYMBOLS 1-30 ARE PRELIMINARY AND SUBJECT TO CHANGE
J 0
(-4875 1225);
DISPLAY 1.021277 (-4875 1225);
PAINT ORANGE (-4875 1225);
FORCEPROP 2 LAST CDS_LIB mstr_symbols
J 0
(-4675 1350);
PAINT ORANGE (-4675 1350);
DISPLAY INVISIBLE (-4675 1350);
FORCEPROP 1 LAST COMMENT_BODY TRUE
J 0
(-4650 1450);
DISPLAY 0.978723 (-4650 1450);
PAINT ORANGE (-4650 1450);
DISPLAY INVISIBLE (-4650 1450);
FORCEADD INTEL_CORP_BPAGE..1
(0 0);
FORCEPROP 1 LAST CDS_CON_LAST_MODIFIED Fri Jun 16 17:48:25 2017
J 0
(-1425 325);
DISPLAY 1.340426 (-1425 325);
PAINT GREEN (-1425 325);
DISPLAY INVISIBLE (-1425 325);
FORCEPROP 1 LAST CUSTOM_TXT_CDS <CURRENT_DESIGN_SHEET> OF <TOTAL_DESIGN_SHEETS>
J 0
(-500 25);
PAINT ORANGE (-500 25);
FORCEPROP 1 LAST CUSTOM_TXT_CDS <CON_LAST_MODIFIED>
J 0
(-4000 100);
PAINT ORANGE (-4000 100);
FORCEPROP 2 LAST CUSTOM_TXT_CDS <XR_PAGE_TITLE>
J 0
(-7890 5250);
DISPLAY 0.638298 (-7890 5250);
PAINT PINK (-7890 5250);
DISPLAY INVISIBLE (-7890 5250);
FORCEPROP 1 LAST SCH_TITLE SKYLAKE - SKT1 - 14 OF 21
J 0
(-7950 50);
DISPLAY 1.212766 (-7950 50);
PAINT GREEN (-7950 50);
FORCEPROP 2 LAST CDS_LIB mstr_symbols
J 0
(0 0);
PAINT ORANGE (0 0);
DISPLAY INVISIBLE (0 0);
FORCEPROP 2 LAST PAGE_BORDER TRUE
J 0
(-7890 5250);
DISPLAY 0.851064 (-7890 5250);
PAINT PINK (-7890 5250);
DISPLAY INVISIBLE (-7890 5250);
FORCEPROP 1 LAST COMMENT_BODY TRUE
J 0
(12 12);
DISPLAY 0.638298 (12 12);
PAINT GREEN (12 12);
DISPLAY INVISIBLE (12 12);
FORCEPROP 2 LAST CDS_XR_PAGE_TITLE CR-68 : @BASEBOARD_FAB2_LIB.BASEBOARD_FAB2(SCH_1):PAGE68
J 0
(-7890 5250);
DISPLAY 0.638298 (-7890 5250);
PAINT PINK (-7890 5250);
DISPLAY INVISIBLE (-7890 5250);
FORCEADD PRELIM..10
(-4090 2640);
PAINT GRAY (-4090 2640);
FORCEPROP 2 LAST CDS_LIB mstr_misc
J 0
(-4090 2640);
PAINT ORANGE (-4090 2640);
DISPLAY INVISIBLE (-4090 2640);
FORCEPROP 1 LAST COMMENT_BODY TRUE
J 0
(-4090 2640);
PAINT ORANGE (-4090 2640);
DISPLAY INVISIBLE (-4090 2640);
WIRE 17 -1 (-2900 3800)(-1800 3800);
FORCEPROP 2 LAST SIG_NAME UPI_CPU1_CPU0_P1P1_DP<19..0>
J 0
(-2485 3810);
DISPLAY 0.617021 (-2485 3810);
PAINT ORANGE (-2485 3810);
WIRE 17 -1 (-2900 3575)(-2900 3800);
WIRE 17 -1 (-2900 3575)(-2900 3525);
WIRE 17 -1 (-2900 3475)(-2900 3525);
WIRE 17 -1 (-2900 3425)(-2900 3475);
WIRE 17 -1 (-2900 3375)(-2900 3425);
WIRE 17 -1 (-2900 1725)(-2900 1675);
WIRE 17 -1 (-2900 3375)(-2900 3325);
WIRE 17 -1 (-2900 3325)(-2900 3225);
WIRE 17 -1 (-2900 1975)(-2900 1725);
WIRE 17 -1 (-2900 2025)(-2900 1975);
WIRE 17 -1 (-2900 3225)(-2900 3175);
WIRE 17 -1 (-2900 3175)(-2900 2975);
WIRE 17 -1 (-2900 2075)(-2900 2025);
WIRE 17 -1 (-2900 2225)(-2900 2075);
WIRE 17 -1 (-2900 2975)(-2900 2925);
WIRE 17 -1 (-2900 2925)(-2900 2875);
WIRE 17 -1 (-2900 2575)(-2900 2225);
WIRE 17 -1 (-2900 2625)(-2900 2575);
WIRE 17 -1 (-2900 2875)(-2900 2825);
WIRE 17 -1 (-2900 2825)(-2900 2625);
WIRE 17 -1 (-2575 1825)(-2575 1775);
WIRE 17 -1 (-2575 1875)(-2575 1825);
WIRE 17 -1 (-2575 1875)(-2575 1925);
WIRE 17 -1 (-2575 3750)(-1800 3750);
FORCEPROP 2 LAST SIG_NAME UPI_CPU1_CPU0_P1P1_DN<19..0>
J 0
(-2485 3760);
DISPLAY 0.617021 (-2485 3760);
PAINT ORANGE (-2485 3760);
WIRE 17 -1 (-2575 3750)(-2575 3675);
WIRE 17 -1 (-2575 2125)(-2575 1925);
WIRE 17 -1 (-2575 2175)(-2575 2125);
WIRE 17 -1 (-2575 3675)(-2575 3625);
WIRE 17 -1 (-2575 3625)(-2575 3275);
WIRE 17 -1 (-2575 2275)(-2575 2175);
WIRE 17 -1 (-2575 2325)(-2575 2275);
WIRE 17 -1 (-2575 3275)(-2575 3125);
WIRE 17 -1 (-2575 3125)(-2575 3075);
WIRE 17 -1 (-2575 2375)(-2575 2325);
WIRE 17 -1 (-2575 2425)(-2575 2375);
WIRE 17 -1 (-2575 3075)(-2575 3025);
WIRE 17 -1 (-2575 3025)(-2575 2775);
WIRE 17 -1 (-2575 2475)(-2575 2425);
WIRE 17 -1 (-2575 2525)(-2575 2475);
WIRE 17 -1 (-2575 2775)(-2575 2725);
WIRE 17 -1 (-2575 2725)(-2575 2525);
WIRE 17 -1 (-6875 3800)(-5325 3800);
FORCEPROP 2 LAST SIG_NAME UPI_CPU0_CPU1_P1P1_DP<19..0>
J 0
(-6825 3810);
DISPLAY 0.617021 (-6825 3810);
PAINT ORANGE (-6825 3810);
WIRE 17 -1 (-5325 3800)(-5325 3575);
WIRE 17 -1 (-5325 3575)(-5325 3525);
WIRE 17 -1 (-5325 3525)(-5325 3475);
WIRE 17 -1 (-5325 3475)(-5325 3425);
WIRE 17 -1 (-5325 3425)(-5325 3225);
WIRE 17 -1 (-5325 3225)(-5325 3175);
WIRE 17 -1 (-5325 3175)(-5325 3075);
WIRE 17 -1 (-5325 3075)(-5325 3025);
WIRE 17 -1 (-5325 2075)(-5325 1675);
WIRE 17 -1 (-5325 2075)(-5325 2225);
WIRE 17 -1 (-5325 3025)(-5325 2975);
WIRE 17 -1 (-5325 2975)(-5325 2925);
WIRE 17 -1 (-5325 2225)(-5325 2275);
WIRE 17 -1 (-5325 2275)(-5325 2325);
WIRE 17 -1 (-5325 2925)(-5325 2875);
WIRE 17 -1 (-5325 2825)(-5325 2875);
WIRE 17 -1 (-5325 2325)(-5325 2575);
WIRE 17 -1 (-5325 2625)(-5325 2575);
WIRE 17 -1 (-5325 2825)(-5325 2775);
WIRE 17 -1 (-5325 2775)(-5325 2625);
WIRE 17 -1 (-5775 1725)(-5775 1775);
WIRE 17 -1 (-5775 1775)(-5775 1825);
WIRE 17 -1 (-5775 1825)(-5775 1875);
WIRE 17 -1 (-5775 1875)(-5775 1925);
WIRE 17 -1 (-5775 1925)(-5775 1975);
WIRE 17 -1 (-6875 3700)(-5775 3700);
FORCEPROP 2 LAST SIG_NAME UPI_CPU0_CPU1_P1P1_DN<19..0>
J 0
(-6825 3710);
DISPLAY 0.617021 (-6825 3710);
PAINT ORANGE (-6825 3710);
WIRE 17 -1 (-5775 3675)(-5775 3700);
WIRE 17 -1 (-5775 1975)(-5775 2025);
WIRE 17 -1 (-5775 2025)(-5775 2125);
WIRE 17 -1 (-5775 3625)(-5775 3675);
WIRE 17 -1 (-5775 3375)(-5775 3625);
WIRE 17 -1 (-5775 2125)(-5775 2175);
WIRE 17 -1 (-5775 2175)(-5775 2375);
WIRE 17 -1 (-5775 3325)(-5775 3375);
WIRE 17 -1 (-5775 3275)(-5775 3325);
WIRE 17 -1 (-5775 2375)(-5775 2425);
WIRE 17 -1 (-5775 2425)(-5775 2475);
WIRE 17 -1 (-5775 3125)(-5775 3275);
WIRE 17 -1 (-5775 2725)(-5775 3125);
WIRE 17 -1 (-5775 2475)(-5775 2525);
WIRE 17 -1 (-5775 2525)(-5775 2725);
WIRE 16 -1 (-5225 2900)(-4900 2900);
WIRE 16 -1 (-5675 3250)(-4900 3250);
WIRE 16 -1 (-5225 2950)(-4900 2950);
WIRE 16 -1 (-2675 3100)(-3300 3100);
WIRE 16 -1 (-5225 1650)(-4900 1650);
WIRE 16 -1 (-5675 1700)(-4900 1700);
WIRE 16 -1 (-5675 1750)(-4900 1750);
WIRE 16 -1 (-5675 1800)(-4900 1800);
WIRE 16 -1 (-5675 1850)(-4900 1850);
WIRE 16 -1 (-5675 1900)(-4900 1900);
WIRE 16 -1 (-5675 1950)(-4900 1950);
WIRE 16 -1 (-5675 2000)(-4900 2000);
WIRE 16 -1 (-5675 2700)(-4900 2700);
WIRE 16 -1 (-5225 2750)(-4900 2750);
WIRE 16 -1 (-5225 2800)(-4900 2800);
WIRE 16 -1 (-5225 2850)(-4900 2850);
WIRE 16 -1 (-5225 3000)(-4900 3000);
WIRE 16 -1 (-5225 3050)(-4900 3050);
WIRE 16 -1 (-5675 3100)(-4900 3100);
WIRE 16 -1 (-5225 3150)(-4900 3150);
WIRE 16 -1 (-5225 3200)(-4900 3200);
WIRE 16 -1 (-5675 3300)(-4900 3300);
WIRE 16 -1 (-5675 3350)(-4900 3350);
WIRE 16 -1 (-5225 3400)(-4900 3400);
WIRE 16 -1 (-5225 3450)(-4900 3450);
WIRE 16 -1 (-5225 3500)(-4900 3500);
WIRE 16 -1 (-5225 3550)(-4900 3550);
WIRE 16 -1 (-5675 3600)(-4900 3600);
WIRE 16 -1 (-5675 3650)(-4900 3650);
WIRE 16 -1 (-4900 2050)(-5225 2050);
WIRE 16 -1 (-5675 2100)(-4900 2100);
WIRE 16 -1 (-5675 2150)(-4900 2150);
WIRE 16 -1 (-4900 2200)(-5225 2200);
WIRE 16 -1 (-4900 2250)(-5225 2250);
WIRE 16 -1 (-4900 2300)(-5225 2300);
WIRE 16 -1 (-5675 2350)(-4900 2350);
WIRE 16 -1 (-5675 2400)(-4900 2400);
WIRE 16 -1 (-5675 2450)(-4900 2450);
WIRE 16 -1 (-5675 2500)(-4900 2500);
WIRE 16 -1 (-5225 2550)(-4900 2550);
WIRE 16 -1 (-4900 2600)(-5225 2600);
WIRE 16 -1 (-3300 1650)(-3000 1650);
WIRE 16 -1 (-3300 1700)(-3000 1700);
WIRE 16 -1 (-2675 1750)(-3300 1750);
WIRE 16 -1 (-2675 1800)(-3300 1800);
WIRE 16 -1 (-3300 1850)(-2675 1850);
WIRE 16 -1 (-2675 1900)(-3300 1900);
WIRE 16 -1 (-3300 1950)(-3000 1950);
WIRE 16 -1 (-3300 2000)(-3000 2000);
WIRE 16 -1 (-2675 2700)(-3300 2700);
WIRE 16 -1 (-2675 2750)(-3300 2750);
WIRE 16 -1 (-3300 2800)(-3000 2800);
WIRE 16 -1 (-3000 2850)(-3300 2850);
WIRE 16 -1 (-3000 2900)(-3300 2900);
WIRE 16 -1 (-3000 2950)(-3300 2950);
WIRE 16 -1 (-2675 3000)(-3300 3000);
WIRE 16 -1 (-2675 3050)(-3300 3050);
WIRE 16 -1 (-3000 3150)(-3300 3150);
WIRE 16 -1 (-3000 3200)(-3300 3200);
WIRE 16 -1 (-2675 3250)(-3300 3250);
WIRE 16 -1 (-3000 3300)(-3300 3300);
WIRE 16 -1 (-3000 3350)(-3300 3350);
WIRE 16 -1 (-3000 3400)(-3300 3400);
WIRE 16 -1 (-3000 3450)(-3300 3450);
WIRE 16 -1 (-3000 3500)(-3300 3500);
WIRE 16 -1 (-3000 3550)(-3300 3550);
WIRE 16 -1 (-2675 3600)(-3300 3600);
WIRE 16 -1 (-2675 3650)(-3300 3650);
WIRE 16 -1 (-3300 2050)(-3000 2050);
WIRE 16 -1 (-2675 2100)(-3300 2100);
WIRE 16 -1 (-2675 2150)(-3300 2150);
WIRE 16 -1 (-3300 2200)(-3000 2200);
WIRE 16 -1 (-3300 2250)(-2675 2250);
WIRE 16 -1 (-2675 2300)(-3300 2300);
WIRE 16 -1 (-2675 2350)(-3300 2350);
WIRE 16 -1 (-2675 2400)(-3300 2400);
WIRE 16 -1 (-2675 2450)(-3300 2450);
WIRE 16 -1 (-2675 2500)(-3300 2500);
WIRE 16 -1 (-3300 2550)(-3000 2550);
WIRE 16 -1 (-3300 2600)(-3000 2600);
FORCENOTE
BOM_COST=PROC_SOCKET
(-7925 200) 0;
DISPLAY LEFT (-7925 200);
DISPLAY 1.723404 (-7925 200);
PAINT PURPLE (-7925 200);
FORCENOTE
ROOM=CPU1
(-7925 325) 0;
DISPLAY LEFT (-7925 325);
DISPLAY 1.723404 (-7925 325);
PAINT PURPLE (-7925 325);
QUIT
